FILE_TYPE = MACRO_DRAWING;
SET COLOR_WIRE YELLOW;
SET COLOR_PROP MONO;
SET COLOR_DOT WHITE;
SET COLOR_ARC YELLOW;
SET COLOR_BODY GREEN;
SET COLOR_NOTE MONO;
SET PROP_DISPLAY VALUE;
SET PAGE_NUMBER P92;
FORCEADD GTL2014..1
R 2
(-1825 4250);
FORCEPROP 1 LAST LOCATION U3P2
J 2
(-1425 4800);
DISPLAY 0.617021 (-1425 4800);
PAINT AQUA (-1425 4800);
FORCEPROP 1 LAST MATERIAL IC
J 2
(-1425 4750);
DISPLAY 0.617021 (-1425 4750);
PAINT SKYBLUE (-1425 4750);
FORCEPROP 2 LASTPIN (-1375 4500) $PN 4
J 0
(-1365 4510);
DISPLAY 0.617021 (-1365 4510);
PAINT ORANGE (-1365 4510);
FORCEPROP 2 LASTPIN (-2275 3900) $PN 8
J 2
(-2285 3910);
DISPLAY 0.617021 (-2285 3910);
PAINT ORANGE (-2285 3910);
FORCEPROP 2 LASTPIN (-2275 3850) $PN 7
J 2
(-2285 3860);
DISPLAY 0.617021 (-2285 3860);
PAINT ORANGE (-2285 3860);
FORCEPROP 2 LASTPIN (-1375 4400) $PN 1
J 0
(-1365 4410);
DISPLAY 0.617021 (-1365 4410);
PAINT ORANGE (-1365 4410);
FORCEPROP 2 LASTPIN (-2275 4250) $PN 6
J 2
(-2285 4260);
DISPLAY 0.617021 (-2285 4260);
PAINT ORANGE (-2285 4260);
FORCEPROP 2 LASTPIN (-2275 4100) $PN 2
J 2
(-2285 4110);
DISPLAY 0.617021 (-2285 4110);
PAINT ORANGE (-2285 4110);
FORCEPROP 2 LASTPIN (-1375 4250) $PN 9
J 0
(-1365 4260);
DISPLAY 0.617021 (-1365 4260);
PAINT ORANGE (-1365 4260);
FORCEPROP 2 LASTPIN (-1375 4200) $PN 10
J 0
(-1365 4210);
DISPLAY 0.617021 (-1365 4210);
PAINT ORANGE (-1365 4210);
FORCEPROP 2 LASTPIN (-1375 4150) $PN 12
J 0
(-1365 4160);
DISPLAY 0.617021 (-1365 4160);
PAINT ORANGE (-1365 4160);
FORCEPROP 2 LASTPIN (-1375 4100) $PN 13
J 0
(-1365 4110);
DISPLAY 0.617021 (-1365 4110);
PAINT ORANGE (-1365 4110);
FORCEPROP 1 LAST PART_NUMBER D66151-001
J 2
(-1425 3725);
DISPLAY 0.617021 (-1425 3725);
PAINT BLUE (-1425 3725);
FORCEPROP 2 LASTPIN (-2275 4200) $PN 5
J 2
(-2285 4210);
DISPLAY 0.617021 (-2285 4210);
PAINT ORANGE (-2285 4210);
FORCEPROP 2 LASTPIN (-2275 4150) $PN 3
J 2
(-2285 4160);
DISPLAY 0.617021 (-2285 4160);
PAINT ORANGE (-2285 4160);
FORCEPROP 2 LASTPIN (-2275 3950) $PN 11
J 2
(-2285 3960);
DISPLAY 0.617021 (-2285 3960);
PAINT ORANGE (-2285 3960);
FORCEPROP 2 LASTPIN (-1375 4550) $PN 14
J 0
(-1365 4560);
DISPLAY 0.617021 (-1365 4560);
PAINT ORANGE (-1365 4560);
FORCEPROP 1 LAST PACK_TYPE SM
J 2
(-1425 4850);
PAINT SKYBLUE (-1425 4850);
DISPLAY INVISIBLE (-1425 4850);
FORCEPROP 2 LAST SEC_TYPE SM
J 0
(-1425 4850);
DISPLAY 1.021277 (-1425 4850);
PAINT ORANGE (-1425 4850);
DISPLAY INVISIBLE (-1425 4850);
FORCEPROP 2 LAST BOM_COST PROC_SIDEBAND
J 2
(-1825 4250);
PAINT MONO (-1825 4250);
DISPLAY INVISIBLE (-1825 4250);
FORCEPROP 2 LAST CDS_LIB mstr_digital
J 0
(-1825 4250);
PAINT ORANGE (-1825 4250);
DISPLAY INVISIBLE (-1825 4250);
FORCEPROP 2 LAST SEC 1
J 0
(-1425 4850);
DISPLAY 0.680851 (-1425 4850);
PAINT MONO (-1425 4850);
DISPLAY INVISIBLE (-1425 4850);
FORCEPROP 2 LAST CDS_LOCATION U3P2
J 2
(-1425 4800);
DISPLAY 0.617021 (-1425 4800);
PAINT AQUA (-1425 4800);
DISPLAY INVISIBLE (-1425 4800);
FORCEPROP 1 LAST PATH I1
J 2
(-1825 4750);
PAINT GREEN (-1825 4750);
DISPLAY INVISIBLE (-1825 4750);
FORCEPROP 2 LAST ROOM PROC_SIDEBAND
J 2
(-1425 4900);
PAINT MONO (-1425 4900);
DISPLAY INVISIBLE (-1425 4900);
FORCEADD PVCCIO_CPU1..1
(-2900 4750);
FORCEPROP 3 LASTPIN (-2900 4700) SIG_NAME PVCCIO_CPU1\g
J 0
(-2890 4710);
DISPLAY 0.659574 (-2890 4710);
PAINT MONO (-2890 4710);
DISPLAY INVISIBLE (-2890 4710);
FORCEPROP 1 LAST VOLTAGE 1.1V
J 0
(-2945 4707);
DISPLAY 0.340426 (-2945 4707);
PAINT SKYBLUE (-2945 4707);
DISPLAY INVISIBLE (-2945 4707);
FORCEPROP 2 LAST CDS_LIB mstr_symbols
J 0
(-2900 4750);
PAINT ORANGE (-2900 4750);
DISPLAY INVISIBLE (-2900 4750);
FORCEPROP 1 LAST PATH I10
J 0
(-2850 4775);
DISPLAY 0.872340 (-2850 4775);
PAINT AQUA (-2850 4775);
DISPLAY INVISIBLE (-2850 4775);
FORCEPROP 1 LAST BODY_TYPE PLUMBING
J 0
(-2945 4707);
DISPLAY 0.340426 (-2945 4707);
PAINT GREEN (-2945 4707);
DISPLAY INVISIBLE (-2945 4707);
FORCEPROP 1 LAST HDL_POWER PVCCIO_CPU1
J 1
(-2900 4800);
DISPLAY 0.872340 (-2900 4800);
PAINT GREEN (-2900 4800);
DISPLAY INVISIBLE (-2900 4800);
FORCEADD RES..2
(-4350 4600);
FORCEPROP 1 LAST LOCATION R7P18
J 0
(-4305 4725);
DISPLAY 0.617021 (-4305 4725);
PAINT AQUA (-4305 4725);
FORCEPROP 1 LAST PART_NUMBER G21796-009
J 0
(-4310 4475);
DISPLAY 0.617021 (-4310 4475);
PAINT BLUE (-4310 4475);
FORCEPROP 1 LAST VALUE 150.0
J 0
(-4305 4675);
DISPLAY 0.617021 (-4305 4675);
PAINT SKYBLUE (-4305 4675);
FORCEPROP 1 LAST TOLERANCE 1%
J 0
(-4305 4625);
DISPLAY 0.617021 (-4305 4625);
PAINT SKYBLUE (-4305 4625);
FORCEPROP 1 LAST PACK_TYPE 0402
J 0
(-4310 4425);
DISPLAY 0.617021 (-4310 4425);
PAINT SKYBLUE (-4310 4425);
FORCEPROP 1 LAST MATERIAL CHIP
J 0
(-4310 4525);
DISPLAY 0.617021 (-4310 4525);
PAINT SKYBLUE (-4310 4525);
FORCEPROP 1 LAST WATTAGE 1/16W
J 0
(-4310 4575);
DISPLAY 0.617021 (-4310 4575);
PAINT SKYBLUE (-4310 4575);
FORCEPROP 1 LASTPIN (-4350 4500) $PN 2
J 0
(-4345 4510);
DISPLAY 0.617021 (-4345 4510);
PAINT MONO (-4345 4510);
FORCEPROP 1 LASTPIN (-4350 4700) $PN 1
J 0
(-4345 4662);
DISPLAY 0.617021 (-4345 4662);
PAINT MONO (-4345 4662);
FORCEPROP 2 LAST CDS_LIB mstr_discrete
J 2
(-4350 4600);
PAINT ORANGE (-4350 4600);
DISPLAY INVISIBLE (-4350 4600);
FORCEPROP 2 LAST BOM_COST PROC
J 0
(-4350 4600);
PAINT MONO (-4350 4600);
DISPLAY INVISIBLE (-4350 4600);
FORCEPROP 2 LAST SEC_TYPE 0402
J 0
(-4300 4825);
DISPLAY 1.021277 (-4300 4825);
PAINT ORANGE (-4300 4825);
DISPLAY INVISIBLE (-4300 4825);
FORCEPROP 2 LAST SEC 1
J 2
(-4300 4825);
DISPLAY 0.936170 (-4300 4825);
PAINT MONO (-4300 4825);
DISPLAY INVISIBLE (-4300 4825);
FORCEPROP 2 LAST CDS_LOCATION R7P18
J 0
(-4305 4725);
DISPLAY 0.617021 (-4305 4725);
PAINT AQUA (-4305 4725);
DISPLAY INVISIBLE (-4305 4725);
FORCEPROP 1 LAST PATH I100
J 0
(-4300 4775);
DISPLAY 0.978723 (-4300 4775);
PAINT WHITE (-4300 4775);
DISPLAY INVISIBLE (-4300 4775);
FORCEPROP 2 LAST ROOM PROC_SIDEBAND
J 0
(-4325 4375);
PAINT ORANGE (-4325 4375);
DISPLAY INVISIBLE (-4325 4375);
FORCEADD RES..2
R 2
(-4450 4600);
FORCEPROP 1 LAST LOCATION R4R2
J 2
(-4495 4725);
DISPLAY 0.617021 (-4495 4725);
PAINT AQUA (-4495 4725);
FORCEPROP 1 LAST PART_NUMBER G21796-009
J 2
(-4490 4475);
DISPLAY 0.617021 (-4490 4475);
PAINT BLUE (-4490 4475);
FORCEPROP 1 LAST VALUE 150.0
J 2
(-4495 4675);
DISPLAY 0.617021 (-4495 4675);
PAINT SKYBLUE (-4495 4675);
FORCEPROP 1 LAST TOLERANCE 1%
J 2
(-4495 4625);
DISPLAY 0.617021 (-4495 4625);
PAINT SKYBLUE (-4495 4625);
FORCEPROP 1 LAST PACK_TYPE 0402
J 2
(-4490 4425);
DISPLAY 0.617021 (-4490 4425);
PAINT SKYBLUE (-4490 4425);
FORCEPROP 1 LAST MATERIAL CHIP
J 2
(-4490 4525);
DISPLAY 0.617021 (-4490 4525);
PAINT SKYBLUE (-4490 4525);
FORCEPROP 1 LAST WATTAGE 1/16W
J 2
(-4490 4575);
DISPLAY 0.617021 (-4490 4575);
PAINT SKYBLUE (-4490 4575);
FORCEPROP 1 LASTPIN (-4450 4500) $PN 2
J 2
(-4455 4510);
DISPLAY 0.617021 (-4455 4510);
PAINT MONO (-4455 4510);
FORCEPROP 1 LASTPIN (-4450 4700) $PN 1
J 2
(-4455 4662);
DISPLAY 0.617021 (-4455 4662);
PAINT MONO (-4455 4662);
FORCEPROP 2 LAST SEC_TYPE 0402
J 0
(-4500 4825);
DISPLAY 1.021277 (-4500 4825);
PAINT ORANGE (-4500 4825);
DISPLAY INVISIBLE (-4500 4825);
FORCEPROP 2 LAST CDS_LIB mstr_discrete
J 0
(-4450 4600);
PAINT ORANGE (-4450 4600);
DISPLAY INVISIBLE (-4450 4600);
FORCEPROP 2 LAST BOM_COST PROC
J 2
(-4450 4600);
PAINT MONO (-4450 4600);
DISPLAY INVISIBLE (-4450 4600);
FORCEPROP 2 LAST SEC 1
J 0
(-4500 4825);
DISPLAY 0.936170 (-4500 4825);
PAINT MONO (-4500 4825);
DISPLAY INVISIBLE (-4500 4825);
FORCEPROP 2 LAST CDS_LOCATION R4R2
J 2
(-4495 4725);
DISPLAY 0.617021 (-4495 4725);
PAINT AQUA (-4495 4725);
DISPLAY INVISIBLE (-4495 4725);
FORCEPROP 1 LAST PATH I101
J 2
(-4500 4775);
DISPLAY 0.978723 (-4500 4775);
PAINT WHITE (-4500 4775);
DISPLAY INVISIBLE (-4500 4775);
FORCEPROP 2 LAST ROOM PROC_SIDEBAND
J 2
(-4475 4375);
PAINT ORANGE (-4475 4375);
DISPLAY INVISIBLE (-4475 4375);
FORCEADD OFFPAGE..1
(-5150 4100);
FORCEPROP 2 LAST $XR0 55 
J 0
(-5371 4100);
DISPLAY 0.638298 (-5371 4100);
PAINT MONO (-5371 4100);
FORCEPROP 2 LAST CDS_LIB mstr_standard
J 0
(-5150 4100);
PAINT ORANGE (-5150 4100);
DISPLAY INVISIBLE (-5150 4100);
FORCEPROP 2 LAST PATH I102
J 0
(-5350 4150);
DISPLAY 1.021277 (-5350 4150);
PAINT ORANGE (-5350 4150);
DISPLAY INVISIBLE (-5350 4150);
FORCEPROP 1 LAST OFFPAGE TRUE
J 0
(-4825 3975);
PAINT GREEN (-4825 3975);
DISPLAY INVISIBLE (-4825 3975);
FORCEPROP 1 LAST COMMENT_BODY TRUE
J 0
(-5025 4000);
DISPLAY 1.170213 (-5025 4000);
PAINT GREEN (-5025 4000);
DISPLAY INVISIBLE (-5025 4000);
FORCEADD OFFPAGE..1
(-5150 4350);
FORCEPROP 2 LAST $XR0 21 
J 0
(-5371 4350);
DISPLAY 0.638298 (-5371 4350);
PAINT MONO (-5371 4350);
FORCEPROP 2 LAST CDS_LIB mstr_standard
J 0
(-5150 4350);
PAINT ORANGE (-5150 4350);
DISPLAY INVISIBLE (-5150 4350);
FORCEPROP 2 LAST PATH I103
J 0
(-5350 4400);
DISPLAY 1.021277 (-5350 4400);
PAINT ORANGE (-5350 4400);
DISPLAY INVISIBLE (-5350 4400);
FORCEPROP 1 LAST OFFPAGE TRUE
J 0
(-4825 4225);
PAINT GREEN (-4825 4225);
DISPLAY INVISIBLE (-4825 4225);
FORCEPROP 1 LAST COMMENT_BODY TRUE
J 0
(-5025 4250);
DISPLAY 1.170213 (-5025 4250);
PAINT GREEN (-5025 4250);
DISPLAY INVISIBLE (-5025 4250);
FORCEADD P3V3..1
(100 5550);
FORCEPROP 3 LASTPIN (100 5500) SIG_NAME P3V3\g
J 0
(110 5510);
DISPLAY 0.659574 (110 5510);
PAINT MONO (110 5510);
DISPLAY INVISIBLE (110 5510);
FORCEPROP 2 LAST CDS_LIB mstr_symbols
J 0
(100 5550);
PAINT ORANGE (100 5550);
DISPLAY INVISIBLE (100 5550);
FORCEPROP 1 LAST SIZE 1B
J 0
(145 5572);
DISPLAY 0.340426 (145 5572);
PAINT GREEN (145 5572);
DISPLAY INVISIBLE (145 5572);
FORCEPROP 1 LAST VOLTAGE 3.3V
J 0
(55 5507);
DISPLAY 0.340426 (55 5507);
PAINT SKYBLUE (55 5507);
DISPLAY INVISIBLE (55 5507);
FORCEPROP 1 LAST PATH I104
J 0
(145 5552);
DISPLAY 0.340426 (145 5552);
PAINT GREEN (145 5552);
DISPLAY INVISIBLE (145 5552);
FORCEPROP 1 LAST BODY_TYPE PLUMBING
J 0
(55 5507);
DISPLAY 0.340426 (55 5507);
PAINT GREEN (55 5507);
DISPLAY INVISIBLE (55 5507);
FORCEPROP 1 LAST HDL_POWER P3V3
J 0
(-225 5425);
DISPLAY 0.872340 (-225 5425);
PAINT ORANGE (-225 5425);
DISPLAY INVISIBLE (-225 5425);
FORCEADD P3V3..1
(350 3250);
FORCEPROP 3 LASTPIN (350 3200) SIG_NAME P3V3\g
J 0
(360 3210);
DISPLAY 0.659574 (360 3210);
PAINT MONO (360 3210);
DISPLAY INVISIBLE (360 3210);
FORCEPROP 1 LAST PATH I105
J 0
(395 3252);
DISPLAY 0.340426 (395 3252);
PAINT GREEN (395 3252);
DISPLAY INVISIBLE (395 3252);
FORCEPROP 1 LAST VOLTAGE 3.3V
J 0
(305 3207);
DISPLAY 0.340426 (305 3207);
PAINT SKYBLUE (305 3207);
DISPLAY INVISIBLE (305 3207);
FORCEPROP 2 LAST CDS_LIB mstr_symbols
J 0
(350 3250);
PAINT ORANGE (350 3250);
DISPLAY INVISIBLE (350 3250);
FORCEPROP 1 LAST SIZE 1B
J 0
(395 3272);
DISPLAY 0.340426 (395 3272);
PAINT GREEN (395 3272);
DISPLAY INVISIBLE (395 3272);
FORCEPROP 1 LAST BODY_TYPE PLUMBING
J 0
(305 3207);
DISPLAY 0.340426 (305 3207);
PAINT GREEN (305 3207);
DISPLAY INVISIBLE (305 3207);
FORCEPROP 1 LAST HDL_POWER P3V3
J 0
(25 3125);
DISPLAY 0.872340 (25 3125);
PAINT ORANGE (25 3125);
DISPLAY INVISIBLE (25 3125);
FORCEADD RES..2
(-100 3050);
FORCEPROP 1 LAST PART_NUMBER G21796-047
J 0
(15 2900);
DISPLAY 0.617021 (15 2900);
PAINT BLUE (15 2900);
FORCEPROP 1 LAST MATERIAL EMPTY
J 0
(15 2950);
DISPLAY 0.617021 (15 2950);
PAINT RED (15 2950);
FORCEPROP 1 LAST WATTAGE 1/16W
J 0
(15 3000);
DISPLAY 0.617021 (15 3000);
PAINT SKYBLUE (15 3000);
FORCEPROP 1 LAST TOLERANCE 1%
J 0
(20 3050);
DISPLAY 0.617021 (20 3050);
PAINT SKYBLUE (20 3050);
FORCEPROP 1 LAST VALUE 49.9
J 0
(20 3100);
DISPLAY 0.617021 (20 3100);
PAINT SKYBLUE (20 3100);
FORCEPROP 1 LAST LOCATION R7W4
J 0
(20 3150);
DISPLAY 0.617021 (20 3150);
PAINT AQUA (20 3150);
FORCEPROP 1 LASTPIN (-100 2950) $PN 2
J 0
(-95 2960);
DISPLAY 0.617021 (-95 2960);
PAINT ORANGE (-95 2960);
FORCEPROP 1 LASTPIN (-100 3150) $PN 1
J 0
(-95 3112);
DISPLAY 0.617021 (-95 3112);
PAINT ORANGE (-95 3112);
FORCEPROP 1 LAST PACK_TYPE 0402
J 0
(15 2850);
DISPLAY 0.617021 (15 2850);
PAINT SKYBLUE (15 2850);
FORCEPROP 2 LAST SEC_TYPE 0402
J 0
(-50 3275);
DISPLAY 1.021277 (-50 3275);
PAINT ORANGE (-50 3275);
DISPLAY INVISIBLE (-50 3275);
FORCEPROP 2 LAST SEC 1
J 0
(-50 3275);
DISPLAY 0.680851 (-50 3275);
PAINT MONO (-50 3275);
DISPLAY INVISIBLE (-50 3275);
FORCEPROP 0 LAST ROOM SB
J 0
(-150 3250);
DISPLAY 1.021277 (-150 3250);
PAINT ORANGE (-150 3250);
DISPLAY INVISIBLE (-150 3250);
FORCEPROP 2 LAST CDS_LIB mstr_discrete
J 0
(-100 3050);
PAINT ORANGE (-100 3050);
DISPLAY INVISIBLE (-100 3050);
FORCEPROP 1 LAST PATH I106
J 0
(-50 3225);
DISPLAY 0.978723 (-50 3225);
PAINT WHITE (-50 3225);
DISPLAY INVISIBLE (-50 3225);
FORCEPROP 2 LAST CDS_LOCATION R7W4
J 0
(-55 3175);
DISPLAY 0.617021 (-55 3175);
PAINT AQUA (-55 3175);
DISPLAY INVISIBLE (-55 3175);
FORCEADD PVCCIO_CPU0..1
(-100 3250);
FORCEPROP 3 LASTPIN (-100 3200) SIG_NAME PVCCIO_CPU0\g
J 0
(-90 3210);
DISPLAY 0.659574 (-90 3210);
PAINT MONO (-90 3210);
DISPLAY INVISIBLE (-90 3210);
FORCEPROP 1 LAST PATH I107
J 0
(-50 3275);
DISPLAY 0.872340 (-50 3275);
PAINT AQUA (-50 3275);
DISPLAY INVISIBLE (-50 3275);
FORCEPROP 2 LAST CDS_LIB mstr_symbols
J 0
(-100 3250);
PAINT ORANGE (-100 3250);
DISPLAY INVISIBLE (-100 3250);
FORCEPROP 1 LAST VOLTAGE 1.1V
J 0
(-145 3207);
DISPLAY 0.340426 (-145 3207);
PAINT SKYBLUE (-145 3207);
DISPLAY INVISIBLE (-145 3207);
FORCEPROP 1 LAST BODY_TYPE PLUMBING
J 0
(-145 3207);
DISPLAY 0.340426 (-145 3207);
PAINT GREEN (-145 3207);
DISPLAY INVISIBLE (-145 3207);
FORCEPROP 1 LAST HDL_POWER PVCCIO_CPU0
J 1
(-100 3300);
DISPLAY 0.872340 (-100 3300);
PAINT GREEN (-100 3300);
DISPLAY INVISIBLE (-100 3300);
FORCEADD RES..2
(-400 5350);
FORCEPROP 1 LASTPIN (-400 5450) $PN 1
J 0
(-395 5412);
DISPLAY 0.617021 (-395 5412);
PAINT ORANGE (-395 5412);
FORCEPROP 1 LASTPIN (-400 5250) $PN 2
J 0
(-395 5260);
DISPLAY 0.617021 (-395 5260);
PAINT ORANGE (-395 5260);
FORCEPROP 1 LAST PART_NUMBER G21796-047
J 0
(-260 5225);
DISPLAY 0.617021 (-260 5225);
PAINT BLUE (-260 5225);
FORCEPROP 1 LAST MATERIAL EMPTY
J 0
(-260 5275);
DISPLAY 0.617021 (-260 5275);
PAINT RED (-260 5275);
FORCEPROP 1 LAST WATTAGE 1/16W
J 0
(-260 5325);
DISPLAY 0.617021 (-260 5325);
PAINT SKYBLUE (-260 5325);
FORCEPROP 1 LAST TOLERANCE 1%
J 0
(-255 5375);
DISPLAY 0.617021 (-255 5375);
PAINT SKYBLUE (-255 5375);
FORCEPROP 1 LAST VALUE 49.9
J 0
(-255 5425);
DISPLAY 0.617021 (-255 5425);
PAINT SKYBLUE (-255 5425);
FORCEPROP 1 LAST LOCATION R3W10
J 0
(-255 5475);
DISPLAY 0.617021 (-255 5475);
PAINT AQUA (-255 5475);
FORCEPROP 1 LAST PACK_TYPE 0402
J 0
(-260 5175);
DISPLAY 0.617021 (-260 5175);
PAINT SKYBLUE (-260 5175);
FORCEPROP 2 LAST CDS_LOCATION R3W10
J 0
(-355 5475);
DISPLAY 0.617021 (-355 5475);
PAINT AQUA (-355 5475);
DISPLAY INVISIBLE (-355 5475);
FORCEPROP 2 LAST SEC_TYPE 0402
J 0
(-350 5575);
DISPLAY 1.021277 (-350 5575);
PAINT ORANGE (-350 5575);
DISPLAY INVISIBLE (-350 5575);
FORCEPROP 2 LAST SEC 1
J 0
(-350 5575);
DISPLAY 0.680851 (-350 5575);
PAINT MONO (-350 5575);
DISPLAY INVISIBLE (-350 5575);
FORCEPROP 0 LAST ROOM SB
J 0
(-450 5550);
DISPLAY 1.021277 (-450 5550);
PAINT ORANGE (-450 5550);
DISPLAY INVISIBLE (-450 5550);
FORCEPROP 2 LAST CDS_LIB mstr_discrete
J 0
(-400 5350);
PAINT ORANGE (-400 5350);
DISPLAY INVISIBLE (-400 5350);
FORCEPROP 1 LAST PATH I108
J 0
(-350 5525);
DISPLAY 0.978723 (-350 5525);
PAINT WHITE (-350 5525);
DISPLAY INVISIBLE (-350 5525);
FORCEADD PVCCIO_CPU0..1
(-400 5550);
FORCEPROP 3 LASTPIN (-400 5500) SIG_NAME PVCCIO_CPU0\g
J 0
(-390 5510);
DISPLAY 0.659574 (-390 5510);
PAINT MONO (-390 5510);
DISPLAY INVISIBLE (-390 5510);
FORCEPROP 1 LAST VOLTAGE 1.1V
J 0
(-445 5507);
DISPLAY 0.340426 (-445 5507);
PAINT SKYBLUE (-445 5507);
DISPLAY INVISIBLE (-445 5507);
FORCEPROP 2 LAST CDS_LIB mstr_symbols
J 0
(-400 5550);
PAINT ORANGE (-400 5550);
DISPLAY INVISIBLE (-400 5550);
FORCEPROP 1 LAST PATH I109
J 0
(-350 5575);
DISPLAY 0.872340 (-350 5575);
PAINT AQUA (-350 5575);
DISPLAY INVISIBLE (-350 5575);
FORCEPROP 1 LAST BODY_TYPE PLUMBING
J 0
(-445 5507);
DISPLAY 0.340426 (-445 5507);
PAINT GREEN (-445 5507);
DISPLAY INVISIBLE (-445 5507);
FORCEPROP 1 LAST HDL_POWER PVCCIO_CPU0
J 1
(-400 5600);
DISPLAY 0.872340 (-400 5600);
PAINT GREEN (-400 5600);
DISPLAY INVISIBLE (-400 5600);
FORCEADD 374R2F-1-GP..1
(100 5325);
FORCEPROP 2 LAST TOLERANCE 1%
J 0
(150 5300);
DISPLAY 0.638298 (150 5300);
PAINT GREEN (150 5300);
FORCEPROP 2 LAST PACK_SIZE 0402
J 0
(150 5200);
DISPLAY 0.638298 (150 5200);
PAINT GREEN (150 5200);
FORCEPROP 2 LAST RATED 1/16W
J 0
(150 5250);
DISPLAY 0.638298 (150 5250);
PAINT GREEN (150 5250);
FORCEPROP 2 LAST ATTRIBUTE 374 OHM
J 0
(150 5350);
DISPLAY 0.638298 (150 5350);
PAINT GREEN (150 5350);
FORCEPROP 1 LAST VALUE 374R2F-1-GP
J 0
(150 5400);
DISPLAY 0.617021 (150 5400);
PAINT GREEN (150 5400);
FORCEPROP 1 LAST LOCATION R3P45
J 0
(150 5455);
DISPLAY 0.617021 (150 5455);
PAINT GREEN (150 5455);
FORCEPROP 1 LAST PATH I110
J 0
(100 5325);
DISPLAY 0.617021 (100 5325);
PAINT GREEN (100 5325);
DISPLAY INVISIBLE (100 5325);
FORCEPROP 1 LAST PACK_TYPE SMD-RG
J 0
(100 5325);
DISPLAY 0.617021 (100 5325);
PAINT GREEN (100 5325);
DISPLAY INVISIBLE (100 5325);
FORCEPROP 1 LAST PART_NUMBER 64.37405.6DL
J 0
(100 5325);
DISPLAY 0.617021 (100 5325);
PAINT GREEN (100 5325);
DISPLAY INVISIBLE (100 5325);
FORCEPROP 2 LAST CDS_LIB w_hdl
J 0
(100 5325);
DISPLAY INVISIBLE (100 5325);
FORCEPROP 1 LAST CDS_LMAN_SYM_OUTLINE -50,75,50,-75
J 0
(100 5325);
DISPLAY 0.468085 (100 5325);
PAINT GREEN (100 5325);
DISPLAY INVISIBLE (100 5325);
FORCEADD 374R2F-1-GP..1
(350 3025);
FORCEPROP 1 LAST LOCATION R7D33
J 0
(400 3155);
DISPLAY 0.617021 (400 3155);
PAINT GREEN (400 3155);
FORCEPROP 2 LAST RATED 1/16W
J 0
(400 2950);
DISPLAY 0.638298 (400 2950);
PAINT GREEN (400 2950);
FORCEPROP 2 LAST TOLERANCE 1%
J 0
(400 3000);
DISPLAY 0.638298 (400 3000);
PAINT GREEN (400 3000);
FORCEPROP 2 LAST ATTRIBUTE 374 OHM
J 0
(400 3050);
DISPLAY 0.638298 (400 3050);
PAINT GREEN (400 3050);
FORCEPROP 1 LAST VALUE 374R2F-1-GP
J 0
(400 3100);
DISPLAY 0.617021 (400 3100);
PAINT GREEN (400 3100);
FORCEPROP 2 LAST PACK_SIZE 0402
J 0
(400 2900);
DISPLAY 0.638298 (400 2900);
PAINT GREEN (400 2900);
FORCEPROP 1 LAST PACK_TYPE SMD-RG
J 0
(350 3025);
DISPLAY 0.617021 (350 3025);
PAINT GREEN (350 3025);
DISPLAY INVISIBLE (350 3025);
FORCEPROP 1 LAST PART_NUMBER 64.37405.6DL
J 0
(350 3025);
DISPLAY 0.617021 (350 3025);
PAINT GREEN (350 3025);
DISPLAY INVISIBLE (350 3025);
FORCEPROP 2 LAST CDS_LIB w_hdl
J 0
(350 3025);
DISPLAY INVISIBLE (350 3025);
FORCEPROP 1 LAST CDS_LMAN_SYM_OUTLINE -50,75,50,-75
J 0
(350 3025);
DISPLAY 0.468085 (350 3025);
PAINT GREEN (350 3025);
DISPLAY INVISIBLE (350 3025);
FORCEPROP 1 LAST PATH I111
J 0
(350 3025);
DISPLAY 0.617021 (350 3025);
PAINT GREEN (350 3025);
DISPLAY INVISIBLE (350 3025);
FORCEADD RES..1
(-125 3750);
FORCEPROP 1 LAST LOCATION R3P46
J 0
(-175 3800);
DISPLAY 0.617021 (-175 3800);
PAINT AQUA (-175 3800);
FORCEPROP 1 LAST VALUE 33.2
J 2
(-150 3650);
DISPLAY 0.617021 (-150 3650);
PAINT SKYBLUE (-150 3650);
FORCEPROP 1 LASTPIN (-225 3750) $PN 1
J 0
(-213 3762);
DISPLAY 0.617021 (-213 3762);
PAINT ORANGE (-213 3762);
FORCEPROP 1 LASTPIN (-25 3750) $PN 2
J 0
(-63 3762);
DISPLAY 0.617021 (-63 3762);
PAINT ORANGE (-63 3762);
FORCEPROP 1 LAST TOLERANCE 1%
J 0
(-125 3650);
DISPLAY 0.617021 (-125 3650);
PAINT SKYBLUE (-125 3650);
FORCEPROP 1 LAST PART_NUMBER G21796-074
J 0
(-25 3800);
DISPLAY 0.617021 (-25 3800);
PAINT BLUE (-25 3800);
FORCEPROP 1 LAST MATERIAL CHIP
J 0
(-25 3650);
DISPLAY 0.617021 (-25 3650);
PAINT SKYBLUE (-25 3650);
FORCEPROP 1 LAST PACK_TYPE 0402
J 0
(150 3650);
DISPLAY 0.617021 (150 3650);
PAINT SKYBLUE (150 3650);
FORCEPROP 1 LAST WATTAGE 1/16W
J 2
(-275 3650);
DISPLAY 0.617021 (-275 3650);
PAINT SKYBLUE (-275 3650);
FORCEPROP 2 LAST SEC_TYPE 0402
J 0
(-175 3950);
DISPLAY 1.021277 (-175 3950);
PAINT ORANGE (-175 3950);
DISPLAY INVISIBLE (-175 3950);
FORCEPROP 2 LAST BOM_COST PROC_SIDEBAND
J 2
(-125 3750);
PAINT MONO (-125 3750);
DISPLAY INVISIBLE (-125 3750);
FORCEPROP 2 LAST CDS_LIB mstr_discrete
J 0
(-125 3750);
PAINT ORANGE (-125 3750);
DISPLAY INVISIBLE (-125 3750);
FORCEPROP 2 LAST SEC 1
J 0
(-175 3950);
DISPLAY 0.680851 (-175 3950);
PAINT MONO (-175 3950);
DISPLAY INVISIBLE (-175 3950);
FORCEPROP 2 LAST CDS_LOCATION R3P46
J 0
(-175 3800);
DISPLAY 0.617021 (-175 3800);
PAINT AQUA (-175 3800);
DISPLAY INVISIBLE (-175 3800);
FORCEPROP 1 LAST PATH I12
J 0
(-175 3900);
DISPLAY 0.978723 (-175 3900);
PAINT WHITE (-175 3900);
DISPLAY INVISIBLE (-175 3900);
FORCEPROP 2 LAST ROOM PROC_SIDEBAND
J 0
(-200 3675);
DISPLAY 0.617021 (-200 3675);
PAINT ORANGE (-200 3675);
DISPLAY INVISIBLE (-200 3675);
FORCEADD RES..1
(-125 4000);
FORCEPROP 1 LAST MATERIAL CHIP
J 0
(-125 3850);
DISPLAY 0.617021 (-125 3850);
PAINT SKYBLUE (-125 3850);
FORCEPROP 1 LAST VALUE 33.2
J 2
(-150 3900);
DISPLAY 0.617021 (-150 3900);
PAINT SKYBLUE (-150 3900);
FORCEPROP 1 LAST TOLERANCE 1%
J 0
(-125 3900);
DISPLAY 0.617021 (-125 3900);
PAINT SKYBLUE (-125 3900);
FORCEPROP 1 LASTPIN (-25 4000) $PN 2
J 0
(-63 4012);
DISPLAY 0.617021 (-63 4012);
PAINT ORANGE (-63 4012);
FORCEPROP 1 LASTPIN (-225 4000) $PN 1
J 0
(-213 4012);
DISPLAY 0.617021 (-213 4012);
PAINT ORANGE (-213 4012);
FORCEPROP 1 LAST LOCATION R3P43
J 0
(-175 4050);
DISPLAY 0.617021 (-175 4050);
PAINT AQUA (-175 4050);
FORCEPROP 1 LAST WATTAGE 1/16W
J 2
(-150 3850);
DISPLAY 0.617021 (-150 3850);
PAINT SKYBLUE (-150 3850);
FORCEPROP 1 LAST PART_NUMBER G21796-074
J 0
(-25 4050);
DISPLAY 0.617021 (-25 4050);
PAINT BLUE (-25 4050);
FORCEPROP 1 LAST PACK_TYPE 0402
J 0
(0 3850);
DISPLAY 0.617021 (0 3850);
PAINT SKYBLUE (0 3850);
FORCEPROP 2 LAST SEC_TYPE 0402
J 0
(-175 4200);
DISPLAY 1.021277 (-175 4200);
PAINT ORANGE (-175 4200);
DISPLAY INVISIBLE (-175 4200);
FORCEPROP 2 LAST BOM_COST PROC_SIDEBAND
J 2
(-125 4000);
PAINT MONO (-125 4000);
DISPLAY INVISIBLE (-125 4000);
FORCEPROP 2 LAST CDS_LIB mstr_discrete
J 0
(-125 4000);
PAINT ORANGE (-125 4000);
DISPLAY INVISIBLE (-125 4000);
FORCEPROP 2 LAST SEC 1
J 0
(-175 4200);
DISPLAY 0.680851 (-175 4200);
PAINT MONO (-175 4200);
DISPLAY INVISIBLE (-175 4200);
FORCEPROP 2 LAST CDS_LOCATION R3P43
J 0
(-175 4050);
DISPLAY 0.617021 (-175 4050);
PAINT AQUA (-175 4050);
DISPLAY INVISIBLE (-175 4050);
FORCEPROP 1 LAST PATH I13
J 0
(-175 4150);
DISPLAY 0.978723 (-175 4150);
PAINT WHITE (-175 4150);
DISPLAY INVISIBLE (-175 4150);
FORCEPROP 2 LAST ROOM PROC_SIDEBAND
J 0
(-200 3925);
DISPLAY 0.617021 (-200 3925);
PAINT ORANGE (-200 3925);
DISPLAY INVISIBLE (-200 3925);
FORCEADD RES..1
(-125 4250);
FORCEPROP 1 LAST PACK_TYPE 0402
J 0
(0 4100);
DISPLAY 0.617021 (0 4100);
PAINT SKYBLUE (0 4100);
FORCEPROP 1 LAST MATERIAL CHIP
J 0
(-125 4100);
DISPLAY 0.617021 (-125 4100);
PAINT SKYBLUE (-125 4100);
FORCEPROP 1 LAST WATTAGE 1/16W
J 2
(-150 4100);
DISPLAY 0.617021 (-150 4100);
PAINT SKYBLUE (-150 4100);
FORCEPROP 1 LAST TOLERANCE 1%
J 0
(-125 4150);
DISPLAY 0.617021 (-125 4150);
PAINT SKYBLUE (-125 4150);
FORCEPROP 1 LASTPIN (-25 4250) $PN 2
J 0
(-63 4262);
DISPLAY 0.617021 (-63 4262);
PAINT ORANGE (-63 4262);
FORCEPROP 1 LASTPIN (-225 4250) $PN 1
J 0
(-213 4262);
DISPLAY 0.617021 (-213 4262);
PAINT ORANGE (-213 4262);
FORCEPROP 1 LAST VALUE 33.2
J 2
(-150 4150);
DISPLAY 0.617021 (-150 4150);
PAINT SKYBLUE (-150 4150);
FORCEPROP 1 LAST LOCATION R3P42
J 0
(-175 4300);
DISPLAY 0.617021 (-175 4300);
PAINT AQUA (-175 4300);
FORCEPROP 1 LAST PART_NUMBER G21796-074
J 0
(-175 4350);
DISPLAY 0.617021 (-175 4350);
PAINT BLUE (-175 4350);
FORCEPROP 2 LAST SEC_TYPE 0402
J 0
(-175 4450);
DISPLAY 1.021277 (-175 4450);
PAINT ORANGE (-175 4450);
DISPLAY INVISIBLE (-175 4450);
FORCEPROP 2 LAST BOM_COST PROC_SIDEBAND
J 2
(-125 4250);
PAINT MONO (-125 4250);
DISPLAY INVISIBLE (-125 4250);
FORCEPROP 2 LAST CDS_LIB mstr_discrete
J 0
(-125 4250);
PAINT ORANGE (-125 4250);
DISPLAY INVISIBLE (-125 4250);
FORCEPROP 2 LAST SEC 1
J 0
(-175 4450);
DISPLAY 0.680851 (-175 4450);
PAINT MONO (-175 4450);
DISPLAY INVISIBLE (-175 4450);
FORCEPROP 2 LAST CDS_LOCATION R3P42
J 0
(-175 4300);
DISPLAY 0.617021 (-175 4300);
PAINT AQUA (-175 4300);
DISPLAY INVISIBLE (-175 4300);
FORCEPROP 1 LAST PATH I14
J 0
(-175 4400);
DISPLAY 0.978723 (-175 4400);
PAINT WHITE (-175 4400);
DISPLAY INVISIBLE (-175 4400);
FORCEPROP 2 LAST ROOM PROC_SIDEBAND
J 0
(-200 4175);
DISPLAY 0.617021 (-200 4175);
PAINT ORANGE (-200 4175);
DISPLAY INVISIBLE (-200 4175);
FORCEADD OFFPAGE..5
R 2
(1050 3750);
FORCEPROP 2 LAST $XR0 191 
J 0
(1239 3750);
DISPLAY 0.638298 (1239 3750);
PAINT MONO (1239 3750);
FORCEPROP 2 LAST CDS_LIB mstr_standard
J 0
(1050 3750);
PAINT ORANGE (1050 3750);
DISPLAY INVISIBLE (1050 3750);
FORCEPROP 2 LAST PATH I16
J 0
(1250 3800);
DISPLAY 1.021277 (1250 3800);
PAINT ORANGE (1250 3800);
DISPLAY INVISIBLE (1250 3800);
FORCEPROP 1 LAST OFFPAGE TRUE
J 2
(725 3625);
PAINT GREEN (725 3625);
DISPLAY INVISIBLE (725 3625);
FORCEPROP 1 LAST COMMENT_BODY TRUE
J 2
(950 3675);
DISPLAY 1.170213 (950 3675);
PAINT GREEN (950 3675);
DISPLAY INVISIBLE (950 3675);
FORCEADD OFFPAGE..2
(1050 4250);
FORCEPROP 2 LAST $XR0 191 
J 0
(1239 4250);
DISPLAY 0.638298 (1239 4250);
PAINT MONO (1239 4250);
FORCEPROP 2 LAST CDS_LIB mstr_standard
J 0
(1050 4250);
PAINT MONO (1050 4250);
DISPLAY INVISIBLE (1050 4250);
FORCEPROP 2 LAST PATH I18
J 0
(1250 4300);
DISPLAY 1.021277 (1250 4300);
PAINT ORANGE (1250 4300);
DISPLAY INVISIBLE (1250 4300);
FORCEPROP 1 LAST OFFPAGE TRUE
J 0
(1375 4125);
PAINT GREEN (1375 4125);
DISPLAY INVISIBLE (1375 4125);
FORCEPROP 1 LAST COMMENT_BODY TRUE
J 0
(1005 4155);
DISPLAY 1.085106 (1005 4155);
PAINT GREEN (1005 4155);
DISPLAY INVISIBLE (1005 4155);
FORCEADD RES..2
(-2850 2325);
FORCEPROP 1 LAST WATTAGE 1/16W
J 0
(-2810 2300);
DISPLAY 0.617021 (-2810 2300);
PAINT SKYBLUE (-2810 2300);
FORCEPROP 1 LAST LOCATION R7E2
J 0
(-2805 2450);
DISPLAY 0.617021 (-2805 2450);
PAINT AQUA (-2805 2450);
FORCEPROP 1 LAST PACK_TYPE 0402
J 0
(-2810 2150);
DISPLAY 0.617021 (-2810 2150);
PAINT SKYBLUE (-2810 2150);
FORCEPROP 1 LAST MATERIAL CHIP
J 0
(-2810 2250);
DISPLAY 0.617021 (-2810 2250);
PAINT SKYBLUE (-2810 2250);
FORCEPROP 1 LASTPIN (-2850 2225) $PN 2
J 0
(-2845 2235);
DISPLAY 0.617021 (-2845 2235);
PAINT ORANGE (-2845 2235);
FORCEPROP 1 LASTPIN (-2850 2425) $PN 1
J 0
(-2845 2387);
DISPLAY 0.617021 (-2845 2387);
PAINT ORANGE (-2845 2387);
FORCEPROP 1 LAST PART_NUMBER G21796-267
J 0
(-2810 2200);
DISPLAY 0.617021 (-2810 2200);
PAINT BLUE (-2810 2200);
FORCEPROP 1 LAST VALUE 75
J 0
(-2805 2400);
DISPLAY 0.617021 (-2805 2400);
PAINT SKYBLUE (-2805 2400);
FORCEPROP 1 LAST TOLERANCE 1.0%
J 0
(-2805 2350);
DISPLAY 0.617021 (-2805 2350);
PAINT SKYBLUE (-2805 2350);
FORCEPROP 2 LAST SEC_TYPE 0402
J 0
(-2800 2550);
DISPLAY 1.021277 (-2800 2550);
PAINT ORANGE (-2800 2550);
DISPLAY INVISIBLE (-2800 2550);
FORCEPROP 2 LAST CDS_LIB mstr_discrete
J 0
(-2850 2325);
PAINT ORANGE (-2850 2325);
DISPLAY INVISIBLE (-2850 2325);
FORCEPROP 2 LAST BOM_COST PROC_SIDEBAND
J 0
(-2850 2325);
PAINT MONO (-2850 2325);
DISPLAY INVISIBLE (-2850 2325);
FORCEPROP 2 LAST SEC 1
J 0
(-2800 2550);
DISPLAY 0.680851 (-2800 2550);
PAINT MONO (-2800 2550);
DISPLAY INVISIBLE (-2800 2550);
FORCEPROP 2 LAST CDS_LOCATION R7E2
J 0
(-2805 2450);
DISPLAY 0.617021 (-2805 2450);
PAINT AQUA (-2805 2450);
DISPLAY INVISIBLE (-2805 2450);
FORCEPROP 1 LAST PATH I19
J 0
(-2800 2500);
DISPLAY 0.978723 (-2800 2500);
PAINT WHITE (-2800 2500);
DISPLAY INVISIBLE (-2800 2500);
FORCEPROP 2 LAST ROOM PROC_SIDEBAND
J 0
(-2825 2100);
PAINT ORANGE (-2825 2100);
DISPLAY INVISIBLE (-2825 2100);
FORCEADD GND..1
(-2550 3725);
FORCEPROP 3 LASTPIN (-2550 3775) SIG_NAME GND\g
J 0
(-2540 3785);
DISPLAY 0.659574 (-2540 3785);
PAINT MONO (-2540 3785);
DISPLAY INVISIBLE (-2540 3785);
FORCEPROP 1 LAST VOLTAGE 0
J 0
(-2550 3725);
PAINT SKYBLUE (-2550 3725);
DISPLAY INVISIBLE (-2550 3725);
FORCEPROP 1 LAST SIZE 1B
J 0
(-2475 3675);
DISPLAY 1.212766 (-2475 3675);
PAINT GREEN (-2475 3675);
DISPLAY INVISIBLE (-2475 3675);
FORCEPROP 2 LAST CDS_LIB mstr_symbols
J 0
(-2550 3725);
PAINT ORANGE (-2550 3725);
DISPLAY INVISIBLE (-2550 3725);
FORCEPROP 1 LAST PATH I2
J 0
(-2475 3725);
DISPLAY 0.872340 (-2475 3725);
PAINT AQUA (-2475 3725);
DISPLAY INVISIBLE (-2475 3725);
FORCEPROP 1 LAST BODY_TYPE PLUMBING
J 0
(-2595 3682);
DISPLAY 0.340426 (-2595 3682);
PAINT GREEN (-2595 3682);
DISPLAY INVISIBLE (-2595 3682);
FORCEPROP 1 LAST HDL_POWER GND
J 0
(-2550 3875);
DISPLAY 1.212766 (-2550 3875);
PAINT GREEN (-2550 3875);
DISPLAY INVISIBLE (-2550 3875);
FORCEADD OFFPAGE..2
(1075 2050);
FORCEPROP 2 LAST $XR0 191 
J 0
(1264 2050);
DISPLAY 0.638298 (1264 2050);
PAINT MONO (1264 2050);
FORCEPROP 2 LAST CDS_LIB mstr_standard
J 0
(1075 2050);
PAINT MONO (1075 2050);
DISPLAY INVISIBLE (1075 2050);
FORCEPROP 2 LAST PATH I20
J 0
(1250 2125);
DISPLAY 1.021277 (1250 2125);
PAINT ORANGE (1250 2125);
DISPLAY INVISIBLE (1250 2125);
FORCEPROP 1 LAST OFFPAGE TRUE
J 0
(1400 1925);
PAINT GREEN (1400 1925);
DISPLAY INVISIBLE (1400 1925);
FORCEPROP 1 LAST COMMENT_BODY TRUE
J 0
(1030 1955);
DISPLAY 1.085106 (1030 1955);
PAINT GREEN (1030 1955);
DISPLAY INVISIBLE (1030 1955);
FORCEADD OFFPAGE..5
R 2
(1075 1550);
FORCEPROP 2 LAST $XR0 191 
J 0
(1264 1550);
DISPLAY 0.638298 (1264 1550);
PAINT MONO (1264 1550);
FORCEPROP 2 LAST CDS_LIB mstr_standard
J 0
(1075 1550);
PAINT ORANGE (1075 1550);
DISPLAY INVISIBLE (1075 1550);
FORCEPROP 2 LAST PATH I22
J 0
(1250 1625);
DISPLAY 1.021277 (1250 1625);
PAINT ORANGE (1250 1625);
DISPLAY INVISIBLE (1250 1625);
FORCEPROP 1 LAST OFFPAGE TRUE
J 2
(750 1425);
PAINT GREEN (750 1425);
DISPLAY INVISIBLE (750 1425);
FORCEPROP 1 LAST COMMENT_BODY TRUE
J 2
(975 1475);
DISPLAY 1.170213 (975 1475);
PAINT GREEN (975 1475);
DISPLAY INVISIBLE (975 1475);
FORCEADD RES..1
(-125 2050);
FORCEPROP 1 LAST PACK_TYPE 0402
J 0
(-25 2000);
DISPLAY 0.617021 (-25 2000);
PAINT SKYBLUE (-25 2000);
FORCEPROP 1 LAST WATTAGE 1/16W
J 2
(-200 1950);
DISPLAY 0.617021 (-200 1950);
PAINT SKYBLUE (-200 1950);
FORCEPROP 1 LAST PART_NUMBER G21796-074
J 0
(-50 1950);
DISPLAY 0.617021 (-50 1950);
PAINT BLUE (-50 1950);
FORCEPROP 1 LAST VALUE 33.2
J 2
(-150 2000);
DISPLAY 0.617021 (-150 2000);
PAINT SKYBLUE (-150 2000);
FORCEPROP 1 LAST TOLERANCE 1%
J 0
(-125 2000);
DISPLAY 0.617021 (-125 2000);
PAINT SKYBLUE (-125 2000);
FORCEPROP 1 LAST MATERIAL CHIP
J 0
(-175 1950);
DISPLAY 0.617021 (-175 1950);
PAINT SKYBLUE (-175 1950);
FORCEPROP 1 LASTPIN (-25 2050) $PN 2
J 0
(-63 2062);
DISPLAY 0.617021 (-63 2062);
PAINT ORANGE (-63 2062);
FORCEPROP 1 LASTPIN (-225 2050) $PN 1
J 0
(-213 2062);
DISPLAY 0.617021 (-213 2062);
PAINT ORANGE (-213 2062);
FORCEPROP 1 LAST LOCATION R7D34
J 0
(-175 2100);
DISPLAY 0.617021 (-175 2100);
PAINT AQUA (-175 2100);
FORCEPROP 2 LAST SEC_TYPE 0402
J 0
(-175 2250);
DISPLAY 1.021277 (-175 2250);
PAINT ORANGE (-175 2250);
DISPLAY INVISIBLE (-175 2250);
FORCEPROP 2 LAST BOM_COST PROC_SIDEBAND
J 2
(-125 2050);
PAINT MONO (-125 2050);
DISPLAY INVISIBLE (-125 2050);
FORCEPROP 2 LAST CDS_LIB mstr_discrete
J 0
(-125 2050);
PAINT ORANGE (-125 2050);
DISPLAY INVISIBLE (-125 2050);
FORCEPROP 2 LAST SEC 1
J 0
(-175 2250);
DISPLAY 0.680851 (-175 2250);
PAINT MONO (-175 2250);
DISPLAY INVISIBLE (-175 2250);
FORCEPROP 2 LAST CDS_LOCATION R7D34
J 0
(-175 2100);
DISPLAY 0.617021 (-175 2100);
PAINT AQUA (-175 2100);
DISPLAY INVISIBLE (-175 2100);
FORCEPROP 1 LAST PATH I24
J 0
(-175 2200);
DISPLAY 0.978723 (-175 2200);
PAINT WHITE (-175 2200);
DISPLAY INVISIBLE (-175 2200);
FORCEPROP 2 LAST ROOM PROC_SIDEBAND
J 0
(-200 1975);
DISPLAY 0.617021 (-200 1975);
PAINT ORANGE (-200 1975);
DISPLAY INVISIBLE (-200 1975);
FORCEADD OFFPAGE..1
(-3225 2050);
FORCEPROP 2 LAST $XR0 21 
J 0
(-3476 2050);
DISPLAY 0.638298 (-3476 2050);
PAINT MONO (-3476 2050);
FORCEPROP 2 LAST CDS_LIB mstr_standard
J 0
(-3225 2050);
PAINT ORANGE (-3225 2050);
DISPLAY INVISIBLE (-3225 2050);
FORCEPROP 2 LAST PATH I27
J 0
(-3425 2100);
DISPLAY 1.021277 (-3425 2100);
PAINT ORANGE (-3425 2100);
DISPLAY INVISIBLE (-3425 2100);
FORCEPROP 1 LAST OFFPAGE TRUE
J 0
(-2900 1925);
PAINT GREEN (-2900 1925);
DISPLAY INVISIBLE (-2900 1925);
FORCEPROP 1 LAST COMMENT_BODY TRUE
J 0
(-3100 1950);
DISPLAY 1.170213 (-3100 1950);
PAINT GREEN (-3100 1950);
DISPLAY INVISIBLE (-3100 1950);
FORCEADD RES..1
(-100 1800);
FORCEPROP 1 LAST PART_NUMBER G21796-074
J 0
(-50 1700);
DISPLAY 0.617021 (-50 1700);
PAINT BLUE (-50 1700);
FORCEPROP 1 LAST VALUE 33.2
J 2
(-125 1750);
DISPLAY 0.617021 (-125 1750);
PAINT SKYBLUE (-125 1750);
FORCEPROP 1 LAST MATERIAL CHIP
J 0
(-175 1700);
DISPLAY 0.617021 (-175 1700);
PAINT SKYBLUE (-175 1700);
FORCEPROP 1 LAST LOCATION R7D31
J 0
(-150 1850);
DISPLAY 0.617021 (-150 1850);
PAINT AQUA (-150 1850);
FORCEPROP 1 LAST TOLERANCE 1%
J 0
(-100 1750);
DISPLAY 0.617021 (-100 1750);
PAINT SKYBLUE (-100 1750);
FORCEPROP 1 LAST PACK_TYPE 0402
J 0
(0 1750);
DISPLAY 0.617021 (0 1750);
PAINT SKYBLUE (0 1750);
FORCEPROP 1 LAST WATTAGE 1/16W
J 2
(-200 1700);
DISPLAY 0.617021 (-200 1700);
PAINT SKYBLUE (-200 1700);
FORCEPROP 1 LASTPIN (0 1800) $PN 2
J 0
(-38 1812);
DISPLAY 0.617021 (-38 1812);
PAINT ORANGE (-38 1812);
FORCEPROP 1 LASTPIN (-200 1800) $PN 1
J 0
(-188 1812);
DISPLAY 0.617021 (-188 1812);
PAINT ORANGE (-188 1812);
FORCEPROP 2 LAST SEC_TYPE 0402
J 0
(-150 2000);
DISPLAY 1.021277 (-150 2000);
PAINT ORANGE (-150 2000);
DISPLAY INVISIBLE (-150 2000);
FORCEPROP 2 LAST BOM_COST PROC_SIDEBAND
J 2
(-100 1800);
PAINT MONO (-100 1800);
DISPLAY INVISIBLE (-100 1800);
FORCEPROP 2 LAST CDS_LIB mstr_discrete
J 0
(-100 1800);
PAINT ORANGE (-100 1800);
DISPLAY INVISIBLE (-100 1800);
FORCEPROP 2 LAST SEC 1
J 0
(-150 2000);
DISPLAY 0.680851 (-150 2000);
PAINT MONO (-150 2000);
DISPLAY INVISIBLE (-150 2000);
FORCEPROP 2 LAST CDS_LOCATION R7D31
J 0
(-150 1850);
DISPLAY 0.617021 (-150 1850);
PAINT AQUA (-150 1850);
DISPLAY INVISIBLE (-150 1850);
FORCEPROP 1 LAST PATH I29
J 0
(-150 1950);
DISPLAY 0.978723 (-150 1950);
PAINT WHITE (-150 1950);
DISPLAY INVISIBLE (-150 1950);
FORCEPROP 2 LAST ROOM PROC_SIDEBAND
J 0
(-175 1725);
DISPLAY 0.617021 (-175 1725);
PAINT ORANGE (-175 1725);
DISPLAY INVISIBLE (-175 1725);
FORCEADD OFFPAGE..1
(-3050 4250);
FORCEPROP 2 LAST $XR0 55 
J 0
(-3301 4250);
DISPLAY 0.638298 (-3301 4250);
PAINT MONO (-3301 4250);
FORCEPROP 2 LAST CDS_LIB mstr_standard
J 0
(-3050 4250);
PAINT ORANGE (-3050 4250);
DISPLAY INVISIBLE (-3050 4250);
FORCEPROP 2 LAST PATH I3
J 0
(-3000 4325);
DISPLAY 1.021277 (-3000 4325);
PAINT ORANGE (-3000 4325);
DISPLAY INVISIBLE (-3000 4325);
FORCEPROP 1 LAST OFFPAGE TRUE
J 0
(-2725 4125);
PAINT GREEN (-2725 4125);
DISPLAY INVISIBLE (-2725 4125);
FORCEPROP 1 LAST COMMENT_BODY TRUE
J 0
(-2925 4150);
DISPLAY 1.170213 (-2925 4150);
PAINT GREEN (-2925 4150);
DISPLAY INVISIBLE (-2925 4150);
FORCEADD RES..1
(-100 1550);
FORCEPROP 1 LAST PART_NUMBER G21796-074
J 0
(-25 1450);
DISPLAY 0.617021 (-25 1450);
PAINT BLUE (-25 1450);
FORCEPROP 1 LAST LOCATION R7D29
J 0
(-150 1600);
DISPLAY 0.617021 (-150 1600);
PAINT AQUA (-150 1600);
FORCEPROP 1 LASTPIN (0 1550) $PN 2
J 0
(-38 1562);
DISPLAY 0.617021 (-38 1562);
PAINT ORANGE (-38 1562);
FORCEPROP 1 LAST PACK_TYPE 0402
J 0
(0 1500);
DISPLAY 0.617021 (0 1500);
PAINT SKYBLUE (0 1500);
FORCEPROP 1 LAST VALUE 33.2
J 2
(-125 1500);
DISPLAY 0.617021 (-125 1500);
PAINT SKYBLUE (-125 1500);
FORCEPROP 1 LAST TOLERANCE 1%
J 0
(-100 1500);
DISPLAY 0.617021 (-100 1500);
PAINT SKYBLUE (-100 1500);
FORCEPROP 1 LAST MATERIAL CHIP
J 0
(-175 1450);
DISPLAY 0.617021 (-175 1450);
PAINT SKYBLUE (-175 1450);
FORCEPROP 1 LAST WATTAGE 1/16W
J 2
(-200 1450);
DISPLAY 0.617021 (-200 1450);
PAINT SKYBLUE (-200 1450);
FORCEPROP 1 LASTPIN (-200 1550) $PN 1
J 0
(-188 1562);
DISPLAY 0.617021 (-188 1562);
PAINT ORANGE (-188 1562);
FORCEPROP 2 LAST BOM_COST PROC_SIDEBAND
J 2
(-100 1550);
PAINT MONO (-100 1550);
DISPLAY INVISIBLE (-100 1550);
FORCEPROP 2 LAST CDS_LIB mstr_discrete
J 0
(-100 1550);
PAINT ORANGE (-100 1550);
DISPLAY INVISIBLE (-100 1550);
FORCEPROP 2 LAST SEC_TYPE 0402
J 0
(-150 1750);
DISPLAY 1.021277 (-150 1750);
PAINT ORANGE (-150 1750);
DISPLAY INVISIBLE (-150 1750);
FORCEPROP 2 LAST SEC 1
J 0
(-150 1750);
DISPLAY 0.680851 (-150 1750);
PAINT MONO (-150 1750);
DISPLAY INVISIBLE (-150 1750);
FORCEPROP 2 LAST CDS_LOCATION R7D29
J 0
(-150 1600);
DISPLAY 0.617021 (-150 1600);
PAINT AQUA (-150 1600);
DISPLAY INVISIBLE (-150 1600);
FORCEPROP 1 LAST PATH I30
J 0
(-150 1700);
DISPLAY 0.978723 (-150 1700);
PAINT WHITE (-150 1700);
DISPLAY INVISIBLE (-150 1700);
FORCEPROP 2 LAST ROOM PROC_SIDEBAND
J 0
(-175 1475);
DISPLAY 0.617021 (-175 1475);
PAINT ORANGE (-175 1475);
DISPLAY INVISIBLE (-175 1475);
FORCEADD GTL2014..1
R 2
(-1750 2050);
FORCEPROP 1 LAST MATERIAL IC
J 2
(-1350 2550);
DISPLAY 0.617021 (-1350 2550);
PAINT SKYBLUE (-1350 2550);
FORCEPROP 2 LASTPIN (-1300 2200) $PN 1
J 0
(-1290 2210);
DISPLAY 0.617021 (-1290 2210);
PAINT ORANGE (-1290 2210);
FORCEPROP 1 LAST PART_NUMBER D66151-001
J 2
(-1350 1525);
DISPLAY 0.617021 (-1350 1525);
PAINT BLUE (-1350 1525);
FORCEPROP 2 LASTPIN (-1300 2300) $PN 4
J 0
(-1290 2310);
DISPLAY 0.617021 (-1290 2310);
PAINT ORANGE (-1290 2310);
FORCEPROP 2 LASTPIN (-2200 1750) $PN 11
J 2
(-2210 1760);
DISPLAY 0.617021 (-2210 1760);
PAINT ORANGE (-2210 1760);
FORCEPROP 2 LASTPIN (-2200 1700) $PN 8
J 2
(-2210 1710);
DISPLAY 0.617021 (-2210 1710);
PAINT ORANGE (-2210 1710);
FORCEPROP 2 LASTPIN (-2200 1650) $PN 7
J 2
(-2210 1660);
DISPLAY 0.617021 (-2210 1660);
PAINT ORANGE (-2210 1660);
FORCEPROP 2 LASTPIN (-2200 2050) $PN 6
J 2
(-2210 2060);
DISPLAY 0.617021 (-2210 2060);
PAINT ORANGE (-2210 2060);
FORCEPROP 2 LASTPIN (-2200 2000) $PN 5
J 2
(-2210 2010);
DISPLAY 0.617021 (-2210 2010);
PAINT ORANGE (-2210 2010);
FORCEPROP 2 LASTPIN (-2200 1950) $PN 3
J 2
(-2210 1960);
DISPLAY 0.617021 (-2210 1960);
PAINT ORANGE (-2210 1960);
FORCEPROP 2 LASTPIN (-2200 1900) $PN 2
J 2
(-2210 1910);
DISPLAY 0.617021 (-2210 1910);
PAINT ORANGE (-2210 1910);
FORCEPROP 2 LASTPIN (-1300 2050) $PN 9
J 0
(-1290 2060);
DISPLAY 0.617021 (-1290 2060);
PAINT ORANGE (-1290 2060);
FORCEPROP 2 LASTPIN (-1300 2000) $PN 10
J 0
(-1290 2010);
DISPLAY 0.617021 (-1290 2010);
PAINT ORANGE (-1290 2010);
FORCEPROP 2 LASTPIN (-1300 1950) $PN 12
J 0
(-1290 1960);
DISPLAY 0.617021 (-1290 1960);
PAINT ORANGE (-1290 1960);
FORCEPROP 2 LASTPIN (-1300 1900) $PN 13
J 0
(-1290 1910);
DISPLAY 0.617021 (-1290 1910);
PAINT ORANGE (-1290 1910);
FORCEPROP 2 LASTPIN (-1300 2350) $PN 14
J 0
(-1290 2360);
DISPLAY 0.617021 (-1290 2360);
PAINT ORANGE (-1290 2360);
FORCEPROP 1 LAST LOCATION U7D2
J 2
(-1350 2600);
DISPLAY 0.617021 (-1350 2600);
PAINT AQUA (-1350 2600);
FORCEPROP 1 LAST PACK_TYPE SM
J 2
(-1350 2650);
PAINT SKYBLUE (-1350 2650);
DISPLAY INVISIBLE (-1350 2650);
FORCEPROP 2 LAST CDS_LIB mstr_digital
J 0
(-1750 2050);
PAINT ORANGE (-1750 2050);
DISPLAY INVISIBLE (-1750 2050);
FORCEPROP 2 LAST BOM_COST PROC_SIDEBAND
J 2
(-1750 2050);
PAINT MONO (-1750 2050);
DISPLAY INVISIBLE (-1750 2050);
FORCEPROP 2 LAST SEC_TYPE SM
J 0
(-1350 2650);
DISPLAY 1.021277 (-1350 2650);
PAINT ORANGE (-1350 2650);
DISPLAY INVISIBLE (-1350 2650);
FORCEPROP 2 LAST SEC 1
J 0
(-1350 2650);
DISPLAY 0.680851 (-1350 2650);
PAINT MONO (-1350 2650);
DISPLAY INVISIBLE (-1350 2650);
FORCEPROP 2 LAST CDS_LOCATION U7D2
J 2
(-1350 2600);
DISPLAY 0.617021 (-1350 2600);
PAINT AQUA (-1350 2600);
DISPLAY INVISIBLE (-1350 2600);
FORCEPROP 1 LAST PATH I32
J 2
(-1750 2550);
PAINT GREEN (-1750 2550);
DISPLAY INVISIBLE (-1750 2550);
FORCEPROP 2 LAST ROOM PROC_SIDEBAND
J 2
(-1350 2700);
PAINT MONO (-1350 2700);
DISPLAY INVISIBLE (-1350 2700);
FORCEADD GND..1
(-2475 1525);
FORCEPROP 3 LASTPIN (-2475 1575) SIG_NAME GND\g
J 0
(-2465 1585);
DISPLAY 0.659574 (-2465 1585);
PAINT MONO (-2465 1585);
DISPLAY INVISIBLE (-2465 1585);
FORCEPROP 1 LAST VOLTAGE 0
J 0
(-2475 1525);
PAINT SKYBLUE (-2475 1525);
DISPLAY INVISIBLE (-2475 1525);
FORCEPROP 2 LAST CDS_LIB mstr_symbols
J 0
(-2475 1525);
PAINT ORANGE (-2475 1525);
DISPLAY INVISIBLE (-2475 1525);
FORCEPROP 1 LAST SIZE 1B
J 0
(-2400 1475);
DISPLAY 1.212766 (-2400 1475);
PAINT GREEN (-2400 1475);
DISPLAY INVISIBLE (-2400 1475);
FORCEPROP 1 LAST PATH I33
J 0
(-2400 1525);
DISPLAY 0.872340 (-2400 1525);
PAINT AQUA (-2400 1525);
DISPLAY INVISIBLE (-2400 1525);
FORCEPROP 1 LAST BODY_TYPE PLUMBING
J 0
(-2520 1482);
DISPLAY 0.340426 (-2520 1482);
PAINT GREEN (-2520 1482);
DISPLAY INVISIBLE (-2520 1482);
FORCEPROP 1 LAST HDL_POWER GND
J 0
(-2475 1675);
DISPLAY 1.212766 (-2475 1675);
PAINT GREEN (-2475 1675);
DISPLAY INVISIBLE (-2475 1675);
FORCEADD OFFPAGE..1
(-3225 1950);
FORCEPROP 2 LAST $XR0 22 
J 0
(-3476 1950);
DISPLAY 0.638298 (-3476 1950);
PAINT MONO (-3476 1950);
FORCEPROP 2 LAST CDS_LIB mstr_standard
J 0
(-3225 1950);
PAINT ORANGE (-3225 1950);
DISPLAY INVISIBLE (-3225 1950);
FORCEPROP 2 LAST PATH I36
J 0
(-3425 2000);
DISPLAY 1.021277 (-3425 2000);
PAINT ORANGE (-3425 2000);
DISPLAY INVISIBLE (-3425 2000);
FORCEPROP 1 LAST OFFPAGE TRUE
J 0
(-2900 1825);
PAINT GREEN (-2900 1825);
DISPLAY INVISIBLE (-2900 1825);
FORCEPROP 1 LAST COMMENT_BODY TRUE
J 0
(-3100 1850);
DISPLAY 1.170213 (-3100 1850);
PAINT GREEN (-3100 1850);
DISPLAY INVISIBLE (-3100 1850);
FORCEADD CAP_A..1
(-400 4800);
FORCEPROP 1 LAST VOLTAGE 16V
J 0
(-350 4800);
DISPLAY 0.617021 (-350 4800);
PAINT SKYBLUE (-350 4800);
FORCEPROP 1 LASTPIN (-400 4900) $PN 1
J 0
(-390 4880);
DISPLAY 0.617021 (-390 4880);
PAINT MONO (-390 4880);
FORCEPROP 1 LAST PACK_TYPE 0402V
J 0
(-350 4600);
DISPLAY 0.617021 (-350 4600);
PAINT SKYBLUE (-350 4600);
FORCEPROP 1 LAST PART_NUMBER A36096-030
J 0
(-350 4650);
DISPLAY 0.617021 (-350 4650);
PAINT BLUE (-350 4650);
FORCEPROP 1 LAST TOLERANCE 10%
J 0
(-350 4750);
DISPLAY 0.617021 (-350 4750);
PAINT SKYBLUE (-350 4750);
FORCEPROP 1 LASTPIN (-400 4700) $PN 2
J 0
(-390 4680);
DISPLAY 0.617021 (-390 4680);
PAINT MONO (-390 4680);
FORCEPROP 1 LAST MATERIAL X7R
J 0
(-350 4700);
DISPLAY 0.617021 (-350 4700);
PAINT SKYBLUE (-350 4700);
FORCEPROP 1 LAST VALUE 0.1UF
J 0
(-350 4850);
DISPLAY 0.617021 (-350 4850);
PAINT SKYBLUE (-350 4850);
FORCEPROP 1 LAST LOCATION C3P49
J 0
(-350 4900);
DISPLAY 0.617021 (-350 4900);
PAINT AQUA (-350 4900);
FORCEPROP 1 LAST PATH I37
J 0
(-350 4950);
DISPLAY 0.978723 (-350 4950);
PAINT WHITE (-350 4950);
DISPLAY INVISIBLE (-350 4950);
FORCEPROP 2 LAST ROOM PROC_SIDEBAND
J 0
(-350 4550);
DISPLAY 0.978723 (-350 4550);
PAINT ORANGE (-350 4550);
DISPLAY INVISIBLE (-350 4550);
FORCEPROP 2 LAST CDS_LOCATION C3P49
J 0
(-350 4900);
DISPLAY 0.617021 (-350 4900);
PAINT AQUA (-350 4900);
DISPLAY INVISIBLE (-350 4900);
FORCEPROP 2 LAST BOM_COST PROC_SIDEBAND
J 0
(-400 4800);
PAINT MONO (-400 4800);
DISPLAY INVISIBLE (-400 4800);
FORCEPROP 2 LAST CDS_LIB dev_discrete
J 0
(-400 4800);
PAINT ORANGE (-400 4800);
DISPLAY INVISIBLE (-400 4800);
FORCEPROP 2 LAST CDS_SEC 1
J 0
(-350 4950);
PAINT ORANGE (-350 4950);
DISPLAY INVISIBLE (-350 4950);
FORCEPROP 2 LAST SEC_TYPE 0402V
J 0
(-350 5000);
PAINT MONO (-350 5000);
DISPLAY INVISIBLE (-350 5000);
FORCEPROP 2 LAST SEC 1
J 0
(-350 5000);
DISPLAY 0.936170 (-350 5000);
PAINT MONO (-350 5000);
DISPLAY INVISIBLE (-350 5000);
FORCEADD RES..2
(100 4800);
FORCEPROP 1 LAST PART_NUMBER G21796-017
J 0
(140 4650);
DISPLAY 0.617021 (140 4650);
PAINT BLUE (140 4650);
FORCEPROP 1 LAST PACK_TYPE 0402
J 0
(140 4600);
DISPLAY 0.617021 (140 4600);
PAINT SKYBLUE (140 4600);
FORCEPROP 1 LAST TOLERANCE 1%
J 0
(145 4800);
DISPLAY 0.617021 (145 4800);
PAINT SKYBLUE (145 4800);
FORCEPROP 1 LAST VALUE 100.0
J 0
(145 4850);
DISPLAY 0.617021 (145 4850);
PAINT SKYBLUE (145 4850);
FORCEPROP 1 LASTPIN (100 4900) $PN 1
J 0
(105 4862);
DISPLAY 0.617021 (105 4862);
PAINT MONO (105 4862);
FORCEPROP 1 LAST WATTAGE 1/16W
J 0
(140 4750);
DISPLAY 0.617021 (140 4750);
PAINT SKYBLUE (140 4750);
FORCEPROP 1 LAST MATERIAL CHIP
J 0
(140 4700);
DISPLAY 0.617021 (140 4700);
PAINT SKYBLUE (140 4700);
FORCEPROP 1 LASTPIN (100 4700) $PN 2
J 0
(105 4710);
DISPLAY 0.617021 (105 4710);
PAINT MONO (105 4710);
FORCEPROP 1 LAST LOCATION R3P49
J 0
(145 4900);
DISPLAY 0.617021 (145 4900);
PAINT AQUA (145 4900);
FORCEPROP 2 LAST ROOM PROC_SIDEBAND
J 2
(400 4575);
DISPLAY 0.978723 (400 4575);
PAINT ORANGE (400 4575);
DISPLAY INVISIBLE (400 4575);
FORCEPROP 1 LAST PATH I38
J 0
(150 4975);
DISPLAY 0.978723 (150 4975);
PAINT WHITE (150 4975);
DISPLAY INVISIBLE (150 4975);
FORCEPROP 2 LAST CDS_LOCATION R3P49
J 0
(145 4925);
DISPLAY 0.617021 (145 4925);
PAINT AQUA (145 4925);
DISPLAY INVISIBLE (145 4925);
FORCEPROP 2 LAST SEC 1
J 0
(150 5025);
DISPLAY 0.936170 (150 5025);
PAINT MONO (150 5025);
DISPLAY INVISIBLE (150 5025);
FORCEPROP 2 LAST BOM_COST PROC_SIDEBAND
J 0
(100 4800);
PAINT MONO (100 4800);
DISPLAY INVISIBLE (100 4800);
FORCEPROP 2 LAST CDS_LIB mstr_discrete
J 2
(100 4800);
PAINT ORANGE (100 4800);
DISPLAY INVISIBLE (100 4800);
FORCEPROP 2 LAST SEC_TYPE 0402
J 0
(150 5025);
PAINT MONO (150 5025);
DISPLAY INVISIBLE (150 5025);
FORCEADD GND..1
(100 4450);
FORCEPROP 3 LASTPIN (100 4500) SIG_NAME GND\g
J 0
(110 4510);
DISPLAY 0.659574 (110 4510);
PAINT MONO (110 4510);
DISPLAY INVISIBLE (110 4510);
FORCEPROP 1 LAST PATH I41
J 0
(175 4450);
DISPLAY 0.872340 (175 4450);
PAINT AQUA (175 4450);
DISPLAY INVISIBLE (175 4450);
FORCEPROP 1 LAST SIZE 1B
J 0
(175 4400);
DISPLAY 1.212766 (175 4400);
PAINT GREEN (175 4400);
DISPLAY INVISIBLE (175 4400);
FORCEPROP 2 LAST CDS_LIB mstr_symbols
J 0
(100 4450);
PAINT ORANGE (100 4450);
DISPLAY INVISIBLE (100 4450);
FORCEPROP 1 LAST VOLTAGE 0
J 0
(100 4450);
PAINT SKYBLUE (100 4450);
DISPLAY INVISIBLE (100 4450);
FORCEPROP 1 LAST BODY_TYPE PLUMBING
J 0
(55 4407);
DISPLAY 0.340426 (55 4407);
PAINT GREEN (55 4407);
DISPLAY INVISIBLE (55 4407);
FORCEPROP 1 LAST HDL_POWER GND
J 0
(100 4600);
DISPLAY 1.212766 (100 4600);
PAINT GREEN (100 4600);
DISPLAY INVISIBLE (100 4600);
FORCEADD P3V3..1
(-1175 4950);
FORCEPROP 3 LASTPIN (-1175 4900) SIG_NAME P3V3\g
J 0
(-1165 4910);
DISPLAY 0.659574 (-1165 4910);
PAINT MONO (-1165 4910);
DISPLAY INVISIBLE (-1165 4910);
FORCEPROP 2 LAST CDS_LIB mstr_symbols
J 0
(-1175 4950);
PAINT ORANGE (-1175 4950);
DISPLAY INVISIBLE (-1175 4950);
FORCEPROP 1 LAST SIZE 1B
J 0
(-1130 4972);
DISPLAY 0.340426 (-1130 4972);
PAINT GREEN (-1130 4972);
DISPLAY INVISIBLE (-1130 4972);
FORCEPROP 1 LAST VOLTAGE 3.3V
J 0
(-1220 4907);
DISPLAY 0.340426 (-1220 4907);
PAINT SKYBLUE (-1220 4907);
DISPLAY INVISIBLE (-1220 4907);
FORCEPROP 1 LAST PATH I42
J 0
(-1130 4952);
DISPLAY 0.340426 (-1130 4952);
PAINT GREEN (-1130 4952);
DISPLAY INVISIBLE (-1130 4952);
FORCEPROP 1 LAST BODY_TYPE PLUMBING
J 0
(-1220 4907);
DISPLAY 0.340426 (-1220 4907);
PAINT GREEN (-1220 4907);
DISPLAY INVISIBLE (-1220 4907);
FORCEPROP 1 LAST HDL_POWER P3V3
J 0
(-1500 4825);
DISPLAY 0.872340 (-1500 4825);
PAINT ORANGE (-1500 4825);
DISPLAY INVISIBLE (-1500 4825);
FORCEADD RES..1
(-675 4400);
FORCEPROP 1 LAST VALUE 1.00K
J 2
(-725 4350);
DISPLAY 0.617021 (-725 4350);
PAINT SKYBLUE (-725 4350);
FORCEPROP 1 LAST PACK_TYPE 0402
J 0
(-500 4350);
DISPLAY 0.617021 (-500 4350);
PAINT SKYBLUE (-500 4350);
FORCEPROP 1 LAST PART_NUMBER G21796-026
J 0
(-1150 4350);
DISPLAY 0.617021 (-1150 4350);
PAINT BLUE (-1150 4350);
FORCEPROP 1 LASTPIN (-575 4400) $PN 2
J 0
(-613 4412);
DISPLAY 0.617021 (-613 4412);
PAINT ORANGE (-613 4412);
FORCEPROP 1 LASTPIN (-775 4400) $PN 1
J 0
(-763 4412);
DISPLAY 0.617021 (-763 4412);
PAINT ORANGE (-763 4412);
FORCEPROP 1 LAST LOCATION R3R1
J 0
(-725 4450);
DISPLAY 0.617021 (-725 4450);
PAINT AQUA (-725 4450);
FORCEPROP 1 LAST WATTAGE 1/16W
J 2
(-450 4450);
DISPLAY 0.617021 (-450 4450);
PAINT SKYBLUE (-450 4450);
FORCEPROP 1 LAST TOLERANCE 1%
J 0
(-600 4350);
DISPLAY 0.617021 (-600 4350);
PAINT SKYBLUE (-600 4350);
FORCEPROP 1 LAST MATERIAL CHIP
J 0
(-400 4450);
DISPLAY 0.617021 (-400 4450);
PAINT SKYBLUE (-400 4450);
FORCEPROP 2 LAST SEC_TYPE 0402
J 0
(-725 4600);
DISPLAY 1.021277 (-725 4600);
PAINT ORANGE (-725 4600);
DISPLAY INVISIBLE (-725 4600);
FORCEPROP 2 LAST CDS_LIB mstr_discrete
J 0
(-675 4400);
PAINT ORANGE (-675 4400);
DISPLAY INVISIBLE (-675 4400);
FORCEPROP 2 LAST BOM_COST PROC_SIDEBAND
J 0
(-675 4400);
PAINT MONO (-675 4400);
DISPLAY INVISIBLE (-675 4400);
FORCEPROP 2 LAST SEC 1
J 0
(-725 4600);
DISPLAY 0.680851 (-725 4600);
PAINT MONO (-725 4600);
DISPLAY INVISIBLE (-725 4600);
FORCEPROP 2 LAST CDS_LOCATION R3R1
J 0
(-725 4450);
DISPLAY 0.617021 (-725 4450);
PAINT AQUA (-725 4450);
DISPLAY INVISIBLE (-725 4450);
FORCEPROP 1 LAST PATH I46
J 0
(-725 4550);
DISPLAY 0.978723 (-725 4550);
PAINT WHITE (-725 4550);
DISPLAY INVISIBLE (-725 4550);
FORCEPROP 2 LAST ROOM PROC_SIDEBAND
J 0
(-725 4550);
PAINT PEACH (-725 4550);
DISPLAY INVISIBLE (-725 4550);
FORCEADD GND..1
(-300 4325);
FORCEPROP 3 LASTPIN (-300 4375) SIG_NAME GND\g
J 0
(-290 4385);
DISPLAY 0.659574 (-290 4385);
PAINT MONO (-290 4385);
DISPLAY INVISIBLE (-290 4385);
FORCEPROP 1 LAST VOLTAGE 0
J 0
(-300 4325);
PAINT SKYBLUE (-300 4325);
DISPLAY INVISIBLE (-300 4325);
FORCEPROP 2 LAST CDS_LIB mstr_symbols
J 0
(-300 4325);
PAINT ORANGE (-300 4325);
DISPLAY INVISIBLE (-300 4325);
FORCEPROP 1 LAST SIZE 1B
J 0
(-225 4275);
DISPLAY 1.170213 (-225 4275);
PAINT GREEN (-225 4275);
DISPLAY INVISIBLE (-225 4275);
FORCEPROP 1 LAST PATH I47
J 0
(-225 4325);
DISPLAY 0.872340 (-225 4325);
PAINT AQUA (-225 4325);
DISPLAY INVISIBLE (-225 4325);
FORCEPROP 1 LAST BODY_TYPE PLUMBING
J 0
(-345 4282);
DISPLAY 0.340426 (-345 4282);
PAINT GREEN (-345 4282);
DISPLAY INVISIBLE (-345 4282);
FORCEPROP 1 LAST HDL_POWER GND
J 0
(-300 4475);
DISPLAY 1.170213 (-300 4475);
PAINT GREEN (-300 4475);
DISPLAY INVISIBLE (-300 4475);
FORCEADD RES..2
(350 2550);
FORCEPROP 1 LAST VALUE 100.0
J 0
(395 2600);
DISPLAY 0.617021 (395 2600);
PAINT SKYBLUE (395 2600);
FORCEPROP 1 LAST TOLERANCE 1%
J 0
(395 2550);
DISPLAY 0.617021 (395 2550);
PAINT SKYBLUE (395 2550);
FORCEPROP 1 LASTPIN (350 2650) $PN 1
J 0
(355 2612);
DISPLAY 0.617021 (355 2612);
PAINT MONO (355 2612);
FORCEPROP 1 LASTPIN (350 2450) $PN 2
J 0
(355 2460);
DISPLAY 0.617021 (355 2460);
PAINT MONO (355 2460);
FORCEPROP 1 LAST LOCATION R7D32
J 0
(395 2650);
DISPLAY 0.617021 (395 2650);
PAINT AQUA (395 2650);
FORCEPROP 1 LAST PACK_TYPE 0402
J 0
(390 2350);
DISPLAY 0.617021 (390 2350);
PAINT SKYBLUE (390 2350);
FORCEPROP 1 LAST MATERIAL CHIP
J 0
(390 2450);
DISPLAY 0.617021 (390 2450);
PAINT SKYBLUE (390 2450);
FORCEPROP 1 LAST WATTAGE 1/16W
J 0
(390 2500);
DISPLAY 0.617021 (390 2500);
PAINT SKYBLUE (390 2500);
FORCEPROP 1 LAST PART_NUMBER G21796-017
J 0
(390 2400);
DISPLAY 0.617021 (390 2400);
PAINT BLUE (390 2400);
FORCEPROP 2 LAST ROOM PROC_SIDEBAND
J 2
(650 2325);
DISPLAY 0.978723 (650 2325);
PAINT ORANGE (650 2325);
DISPLAY INVISIBLE (650 2325);
FORCEPROP 1 LAST PATH I48
J 0
(400 2725);
DISPLAY 0.978723 (400 2725);
PAINT WHITE (400 2725);
DISPLAY INVISIBLE (400 2725);
FORCEPROP 2 LAST CDS_LOCATION R7D32
J 0
(395 2675);
DISPLAY 0.617021 (395 2675);
PAINT AQUA (395 2675);
DISPLAY INVISIBLE (395 2675);
FORCEPROP 2 LAST SEC 1
J 0
(400 2775);
DISPLAY 0.680851 (400 2775);
PAINT MONO (400 2775);
DISPLAY INVISIBLE (400 2775);
FORCEPROP 2 LAST SEC_TYPE 0402
J 0
(400 2775);
DISPLAY 1.021277 (400 2775);
PAINT ORANGE (400 2775);
DISPLAY INVISIBLE (400 2775);
FORCEPROP 2 LAST BOM_COST PROC_SIDEBAND
J 0
(350 2550);
PAINT MONO (350 2550);
DISPLAY INVISIBLE (350 2550);
FORCEPROP 2 LAST CDS_LIB mstr_discrete
J 2
(350 2550);
PAINT ORANGE (350 2550);
DISPLAY INVISIBLE (350 2550);
FORCEADD GND..1
(350 2200);
FORCEPROP 3 LASTPIN (350 2250) SIG_NAME GND\g
J 0
(360 2260);
DISPLAY 0.659574 (360 2260);
PAINT MONO (360 2260);
DISPLAY INVISIBLE (360 2260);
FORCEPROP 1 LAST PATH I49
J 0
(425 2200);
DISPLAY 0.872340 (425 2200);
PAINT AQUA (425 2200);
DISPLAY INVISIBLE (425 2200);
FORCEPROP 2 LAST CDS_LIB mstr_symbols
J 0
(350 2200);
PAINT ORANGE (350 2200);
DISPLAY INVISIBLE (350 2200);
FORCEPROP 1 LAST SIZE 1B
J 0
(425 2150);
DISPLAY 1.212766 (425 2150);
PAINT GREEN (425 2150);
DISPLAY INVISIBLE (425 2150);
FORCEPROP 1 LAST VOLTAGE 0
J 0
(350 2200);
PAINT SKYBLUE (350 2200);
DISPLAY INVISIBLE (350 2200);
FORCEPROP 1 LAST BODY_TYPE PLUMBING
J 0
(305 2157);
DISPLAY 0.340426 (305 2157);
PAINT GREEN (305 2157);
DISPLAY INVISIBLE (305 2157);
FORCEPROP 1 LAST HDL_POWER GND
J 0
(350 2350);
DISPLAY 1.212766 (350 2350);
PAINT GREEN (350 2350);
DISPLAY INVISIBLE (350 2350);
FORCEADD OFFPAGE..1
(-3050 4150);
FORCEPROP 2 LAST $XR0 56 
J 0
(-3301 4150);
DISPLAY 0.638298 (-3301 4150);
PAINT MONO (-3301 4150);
FORCEPROP 2 LAST CDS_LIB mstr_standard
J 0
(-3050 4150);
PAINT ORANGE (-3050 4150);
DISPLAY INVISIBLE (-3050 4150);
FORCEPROP 2 LAST PATH I5
J 0
(-3000 4225);
DISPLAY 1.021277 (-3000 4225);
PAINT ORANGE (-3000 4225);
DISPLAY INVISIBLE (-3000 4225);
FORCEPROP 1 LAST OFFPAGE TRUE
J 0
(-2725 4025);
PAINT GREEN (-2725 4025);
DISPLAY INVISIBLE (-2725 4025);
FORCEPROP 1 LAST COMMENT_BODY TRUE
J 0
(-2925 4050);
DISPLAY 1.170213 (-2925 4050);
PAINT GREEN (-2925 4050);
DISPLAY INVISIBLE (-2925 4050);
FORCEADD CAP_A..1
(-100 2550);
FORCEPROP 1 LAST TOLERANCE 10%
J 0
(-50 2500);
DISPLAY 0.617021 (-50 2500);
PAINT SKYBLUE (-50 2500);
FORCEPROP 1 LAST PACK_TYPE 0402V
J 0
(-50 2350);
DISPLAY 0.617021 (-50 2350);
PAINT SKYBLUE (-50 2350);
FORCEPROP 1 LAST MATERIAL X7R
J 0
(-50 2450);
DISPLAY 0.617021 (-50 2450);
PAINT SKYBLUE (-50 2450);
FORCEPROP 1 LASTPIN (-100 2450) $PN 2
J 0
(-90 2430);
DISPLAY 0.617021 (-90 2430);
PAINT MONO (-90 2430);
FORCEPROP 1 LAST VOLTAGE 16V
J 0
(-50 2550);
DISPLAY 0.617021 (-50 2550);
PAINT SKYBLUE (-50 2550);
FORCEPROP 1 LAST PART_NUMBER A36096-030
J 0
(-50 2400);
DISPLAY 0.617021 (-50 2400);
PAINT BLUE (-50 2400);
FORCEPROP 1 LAST VALUE 0.1UF
J 0
(-50 2600);
DISPLAY 0.617021 (-50 2600);
PAINT SKYBLUE (-50 2600);
FORCEPROP 1 LASTPIN (-100 2650) $PN 1
J 0
(-90 2630);
DISPLAY 0.617021 (-90 2630);
PAINT MONO (-90 2630);
FORCEPROP 1 LAST LOCATION C7D5
J 0
(-50 2650);
DISPLAY 0.617021 (-50 2650);
PAINT AQUA (-50 2650);
FORCEPROP 1 LAST PATH I52
J 0
(-50 2700);
DISPLAY 0.978723 (-50 2700);
PAINT WHITE (-50 2700);
DISPLAY INVISIBLE (-50 2700);
FORCEPROP 2 LAST ROOM PROC_SIDEBAND
J 0
(-50 2300);
DISPLAY 0.978723 (-50 2300);
PAINT ORANGE (-50 2300);
DISPLAY INVISIBLE (-50 2300);
FORCEPROP 2 LAST CDS_LOCATION C7D5
J 0
(-50 2650);
DISPLAY 0.617021 (-50 2650);
PAINT AQUA (-50 2650);
DISPLAY INVISIBLE (-50 2650);
FORCEPROP 2 LAST BOM_COST PROC_SIDEBAND
J 0
(-100 2550);
PAINT MONO (-100 2550);
DISPLAY INVISIBLE (-100 2550);
FORCEPROP 2 LAST CDS_LIB dev_discrete
J 0
(-100 2550);
PAINT ORANGE (-100 2550);
DISPLAY INVISIBLE (-100 2550);
FORCEPROP 2 LAST CDS_SEC 1
J 0
(-50 2700);
PAINT ORANGE (-50 2700);
DISPLAY INVISIBLE (-50 2700);
FORCEPROP 2 LAST SEC_TYPE 0402V
J 0
(-50 2750);
PAINT MONO (-50 2750);
DISPLAY INVISIBLE (-50 2750);
FORCEPROP 2 LAST SEC 1
J 0
(-50 2750);
DISPLAY 0.936170 (-50 2750);
PAINT MONO (-50 2750);
DISPLAY INVISIBLE (-50 2750);
FORCEADD GND..1
(-225 2125);
FORCEPROP 3 LASTPIN (-225 2175) SIG_NAME GND\g
J 0
(-215 2185);
DISPLAY 0.659574 (-215 2185);
PAINT MONO (-215 2185);
DISPLAY INVISIBLE (-215 2185);
FORCEPROP 1 LAST VOLTAGE 0
J 0
(-225 2125);
PAINT SKYBLUE (-225 2125);
DISPLAY INVISIBLE (-225 2125);
FORCEPROP 2 LAST CDS_LIB mstr_symbols
J 0
(-225 2125);
PAINT ORANGE (-225 2125);
DISPLAY INVISIBLE (-225 2125);
FORCEPROP 1 LAST SIZE 1B
J 0
(-150 2075);
DISPLAY 1.170213 (-150 2075);
PAINT GREEN (-150 2075);
DISPLAY INVISIBLE (-150 2075);
FORCEPROP 1 LAST PATH I53
J 0
(-150 2125);
DISPLAY 0.872340 (-150 2125);
PAINT AQUA (-150 2125);
DISPLAY INVISIBLE (-150 2125);
FORCEPROP 1 LAST BODY_TYPE PLUMBING
J 0
(-270 2082);
DISPLAY 0.340426 (-270 2082);
PAINT GREEN (-270 2082);
DISPLAY INVISIBLE (-270 2082);
FORCEPROP 1 LAST HDL_POWER GND
J 0
(-225 2275);
DISPLAY 1.170213 (-225 2275);
PAINT GREEN (-225 2275);
DISPLAY INVISIBLE (-225 2275);
FORCEADD RES..1
(-600 2200);
FORCEPROP 1 LAST LOCATION R7D26
J 0
(-650 2250);
DISPLAY 0.617021 (-650 2250);
PAINT AQUA (-650 2250);
FORCEPROP 1 LASTPIN (-500 2200) $PN 2
J 0
(-538 2212);
DISPLAY 0.617021 (-538 2212);
PAINT ORANGE (-538 2212);
FORCEPROP 1 LAST TOLERANCE 1%
J 0
(-525 2150);
DISPLAY 0.617021 (-525 2150);
PAINT SKYBLUE (-525 2150);
FORCEPROP 1 LAST PART_NUMBER G21796-026
J 0
(-1075 2150);
DISPLAY 0.617021 (-1075 2150);
PAINT BLUE (-1075 2150);
FORCEPROP 1 LAST VALUE 1.00K
J 2
(-650 2150);
DISPLAY 0.617021 (-650 2150);
PAINT SKYBLUE (-650 2150);
FORCEPROP 1 LAST PACK_TYPE 0402
J 0
(-425 2150);
DISPLAY 0.617021 (-425 2150);
PAINT SKYBLUE (-425 2150);
FORCEPROP 1 LAST WATTAGE 1/16W
J 2
(-375 2250);
DISPLAY 0.617021 (-375 2250);
PAINT SKYBLUE (-375 2250);
FORCEPROP 1 LASTPIN (-700 2200) $PN 1
J 0
(-688 2212);
DISPLAY 0.617021 (-688 2212);
PAINT ORANGE (-688 2212);
FORCEPROP 1 LAST MATERIAL CHIP
J 0
(-325 2250);
DISPLAY 0.617021 (-325 2250);
PAINT SKYBLUE (-325 2250);
FORCEPROP 2 LAST BOM_COST PROC_SIDEBAND
J 0
(-600 2200);
PAINT MONO (-600 2200);
DISPLAY INVISIBLE (-600 2200);
FORCEPROP 2 LAST CDS_LIB mstr_discrete
J 0
(-600 2200);
PAINT ORANGE (-600 2200);
DISPLAY INVISIBLE (-600 2200);
FORCEPROP 2 LAST SEC_TYPE 0402
J 0
(-650 2400);
DISPLAY 1.021277 (-650 2400);
PAINT ORANGE (-650 2400);
DISPLAY INVISIBLE (-650 2400);
FORCEPROP 2 LAST SEC 1
J 0
(-650 2400);
DISPLAY 0.680851 (-650 2400);
PAINT MONO (-650 2400);
DISPLAY INVISIBLE (-650 2400);
FORCEPROP 2 LAST CDS_LOCATION R7D26
J 0
(-650 2250);
DISPLAY 0.617021 (-650 2250);
PAINT AQUA (-650 2250);
DISPLAY INVISIBLE (-650 2250);
FORCEPROP 1 LAST PATH I54
J 0
(-650 2350);
DISPLAY 0.978723 (-650 2350);
PAINT WHITE (-650 2350);
DISPLAY INVISIBLE (-650 2350);
FORCEPROP 2 LAST ROOM PROC_SIDEBAND
J 0
(-650 2350);
PAINT PEACH (-650 2350);
DISPLAY INVISIBLE (-650 2350);
FORCEADD P3V3..1
(-1050 2750);
FORCEPROP 3 LASTPIN (-1050 2700) SIG_NAME P3V3\g
J 0
(-1040 2710);
DISPLAY 0.659574 (-1040 2710);
PAINT MONO (-1040 2710);
DISPLAY INVISIBLE (-1040 2710);
FORCEPROP 1 LAST PATH I58
J 0
(-1005 2752);
DISPLAY 0.340426 (-1005 2752);
PAINT GREEN (-1005 2752);
DISPLAY INVISIBLE (-1005 2752);
FORCEPROP 1 LAST VOLTAGE 3.3V
J 0
(-1095 2707);
DISPLAY 0.340426 (-1095 2707);
PAINT SKYBLUE (-1095 2707);
DISPLAY INVISIBLE (-1095 2707);
FORCEPROP 2 LAST CDS_LIB mstr_symbols
J 0
(-1050 2750);
PAINT ORANGE (-1050 2750);
DISPLAY INVISIBLE (-1050 2750);
FORCEPROP 1 LAST SIZE 1B
J 0
(-1005 2772);
DISPLAY 0.340426 (-1005 2772);
PAINT GREEN (-1005 2772);
DISPLAY INVISIBLE (-1005 2772);
FORCEPROP 1 LAST BODY_TYPE PLUMBING
J 0
(-1095 2707);
DISPLAY 0.340426 (-1095 2707);
PAINT GREEN (-1095 2707);
DISPLAY INVISIBLE (-1095 2707);
FORCEPROP 1 LAST HDL_POWER P3V3
J 0
(-1375 2625);
DISPLAY 0.872340 (-1375 2625);
PAINT ORANGE (-1375 2625);
DISPLAY INVISIBLE (-1375 2625);
FORCEADD OFFPAGE..1
(-3050 4100);
FORCEPROP 2 LAST $XR0 118 
J 0
(-3332 4100);
DISPLAY 0.638298 (-3332 4100);
PAINT MONO (-3332 4100);
FORCEPROP 2 LAST CDS_LIB mstr_standard
J 0
(-3050 4100);
PAINT ORANGE (-3050 4100);
DISPLAY INVISIBLE (-3050 4100);
FORCEPROP 2 LAST PATH I59
J 0
(-3325 4150);
DISPLAY 1.021277 (-3325 4150);
PAINT ORANGE (-3325 4150);
DISPLAY INVISIBLE (-3325 4150);
FORCEPROP 1 LAST OFFPAGE TRUE
J 0
(-2725 3975);
PAINT GREEN (-2725 3975);
DISPLAY INVISIBLE (-2725 3975);
FORCEPROP 1 LAST COMMENT_BODY TRUE
J 0
(-2925 4000);
DISPLAY 1.170213 (-2925 4000);
PAINT GREEN (-2925 4000);
DISPLAY INVISIBLE (-2925 4000);
FORCEADD OFFPAGE..5
R 2
(1050 3550);
FORCEPROP 2 LAST $XR0 191 
J 0
(1239 3550);
DISPLAY 0.638298 (1239 3550);
PAINT MONO (1239 3550);
FORCEPROP 2 LAST CDS_LIB mstr_standard
J 0
(1050 3550);
PAINT ORANGE (1050 3550);
DISPLAY INVISIBLE (1050 3550);
FORCEPROP 2 LAST PATH I60
J 0
(1250 3600);
DISPLAY 1.021277 (1250 3600);
PAINT ORANGE (1250 3600);
DISPLAY INVISIBLE (1250 3600);
FORCEPROP 1 LAST OFFPAGE TRUE
J 2
(725 3425);
PAINT GREEN (725 3425);
DISPLAY INVISIBLE (725 3425);
FORCEPROP 1 LAST COMMENT_BODY TRUE
J 2
(950 3475);
DISPLAY 1.170213 (950 3475);
PAINT GREEN (950 3475);
DISPLAY INVISIBLE (950 3475);
FORCEADD RES..1
(-125 3550);
FORCEPROP 1 LAST MATERIAL CHIP
J 0
(-325 3450);
DISPLAY 0.617021 (-325 3450);
PAINT SKYBLUE (-325 3450);
FORCEPROP 1 LAST WATTAGE 1/16W
J 2
(-350 3450);
DISPLAY 0.617021 (-350 3450);
PAINT SKYBLUE (-350 3450);
FORCEPROP 1 LAST TOLERANCE 1%
J 0
(-125 3450);
DISPLAY 0.617021 (-125 3450);
PAINT SKYBLUE (-125 3450);
FORCEPROP 1 LASTPIN (-25 3550) $PN 2
J 0
(-63 3562);
DISPLAY 0.617021 (-63 3562);
PAINT ORANGE (-63 3562);
FORCEPROP 1 LASTPIN (-225 3550) $PN 1
J 0
(-213 3562);
DISPLAY 0.617021 (-213 3562);
PAINT ORANGE (-213 3562);
FORCEPROP 1 LAST VALUE 33.2
J 2
(-150 3450);
DISPLAY 0.617021 (-150 3450);
PAINT SKYBLUE (-150 3450);
FORCEPROP 1 LAST LOCATION R3R3
J 0
(-175 3600);
DISPLAY 0.617021 (-175 3600);
PAINT AQUA (-175 3600);
FORCEPROP 1 LAST PACK_TYPE 0402
J 0
(0 3450);
DISPLAY 0.617021 (0 3450);
PAINT SKYBLUE (0 3450);
FORCEPROP 1 LAST PART_NUMBER G21796-074
J 0
(150 3450);
DISPLAY 0.617021 (150 3450);
PAINT BLUE (150 3450);
FORCEPROP 2 LAST SEC_TYPE 0402
J 0
(-175 3750);
DISPLAY 1.021277 (-175 3750);
PAINT ORANGE (-175 3750);
DISPLAY INVISIBLE (-175 3750);
FORCEPROP 2 LAST BOM_COST PROC_SIDEBAND
J 2
(-125 3550);
PAINT MONO (-125 3550);
DISPLAY INVISIBLE (-125 3550);
FORCEPROP 2 LAST CDS_LIB mstr_discrete
J 0
(-125 3550);
PAINT ORANGE (-125 3550);
DISPLAY INVISIBLE (-125 3550);
FORCEPROP 2 LAST SEC 1
J 0
(-175 3750);
DISPLAY 0.680851 (-175 3750);
PAINT MONO (-175 3750);
DISPLAY INVISIBLE (-175 3750);
FORCEPROP 2 LAST CDS_LOCATION R3R3
J 0
(-175 3600);
DISPLAY 0.617021 (-175 3600);
PAINT AQUA (-175 3600);
DISPLAY INVISIBLE (-175 3600);
FORCEPROP 1 LAST PATH I61
J 0
(-175 3700);
DISPLAY 0.978723 (-175 3700);
PAINT WHITE (-175 3700);
DISPLAY INVISIBLE (-175 3700);
FORCEPROP 2 LAST ROOM PROC_SIDEBAND
J 0
(-200 3475);
DISPLAY 0.617021 (-200 3475);
PAINT ORANGE (-200 3475);
DISPLAY INVISIBLE (-200 3475);
FORCEADD OFFPAGE..1
(-5125 1550);
FORCEPROP 2 LAST $XR0 21 
J 0
(-5346 1550);
DISPLAY 0.638298 (-5346 1550);
PAINT MONO (-5346 1550);
FORCEPROP 2 LAST CDS_LIB mstr_standard
J 0
(-5125 1550);
PAINT ORANGE (-5125 1550);
DISPLAY INVISIBLE (-5125 1550);
FORCEPROP 2 LAST PATH I62
J 0
(-5375 1600);
DISPLAY 1.021277 (-5375 1600);
PAINT ORANGE (-5375 1600);
DISPLAY INVISIBLE (-5375 1600);
FORCEPROP 1 LAST OFFPAGE TRUE
J 0
(-4800 1425);
PAINT GREEN (-4800 1425);
DISPLAY INVISIBLE (-4800 1425);
FORCEPROP 1 LAST COMMENT_BODY TRUE
J 0
(-5000 1450);
DISPLAY 1.170213 (-5000 1450);
PAINT GREEN (-5000 1450);
DISPLAY INVISIBLE (-5000 1450);
FORCEADD OFFPAGE..1
(-5125 1275);
FORCEPROP 2 LAST $XR0 55 
J 0
(-5346 1275);
DISPLAY 0.638298 (-5346 1275);
PAINT MONO (-5346 1275);
FORCEPROP 2 LAST CDS_LIB mstr_standard
J 0
(-5125 1275);
PAINT ORANGE (-5125 1275);
DISPLAY INVISIBLE (-5125 1275);
FORCEPROP 2 LAST PATH I63
J 0
(-5375 1325);
DISPLAY 1.021277 (-5375 1325);
PAINT ORANGE (-5375 1325);
DISPLAY INVISIBLE (-5375 1325);
FORCEPROP 1 LAST OFFPAGE TRUE
J 0
(-4800 1150);
PAINT GREEN (-4800 1150);
DISPLAY INVISIBLE (-4800 1150);
FORCEPROP 1 LAST COMMENT_BODY TRUE
J 0
(-5000 1175);
DISPLAY 1.170213 (-5000 1175);
PAINT GREEN (-5000 1175);
DISPLAY INVISIBLE (-5000 1175);
FORCEADD RES..2
R 2
(-4600 1825);
FORCEPROP 1 LAST LOCATION R6D9
J 2
(-4645 1950);
DISPLAY 0.617021 (-4645 1950);
PAINT AQUA (-4645 1950);
FORCEPROP 1 LAST PART_NUMBER G21796-009
J 2
(-4640 1700);
DISPLAY 0.617021 (-4640 1700);
PAINT BLUE (-4640 1700);
FORCEPROP 1 LAST TOLERANCE 1%
J 2
(-4645 1850);
DISPLAY 0.617021 (-4645 1850);
PAINT SKYBLUE (-4645 1850);
FORCEPROP 1 LAST PACK_TYPE 0402
J 2
(-4640 1650);
DISPLAY 0.617021 (-4640 1650);
PAINT SKYBLUE (-4640 1650);
FORCEPROP 1 LAST MATERIAL CHIP
J 2
(-4640 1750);
DISPLAY 0.617021 (-4640 1750);
PAINT SKYBLUE (-4640 1750);
FORCEPROP 1 LAST WATTAGE 1/16W
J 2
(-4640 1800);
DISPLAY 0.617021 (-4640 1800);
PAINT SKYBLUE (-4640 1800);
FORCEPROP 1 LASTPIN (-4600 1725) $PN 2
J 2
(-4605 1735);
DISPLAY 0.617021 (-4605 1735);
PAINT ORANGE (-4605 1735);
FORCEPROP 1 LASTPIN (-4600 1925) $PN 1
J 2
(-4605 1887);
DISPLAY 0.617021 (-4605 1887);
PAINT ORANGE (-4605 1887);
FORCEPROP 1 LAST VALUE 150.0
J 2
(-4645 1900);
DISPLAY 0.617021 (-4645 1900);
PAINT SKYBLUE (-4645 1900);
FORCEPROP 2 LAST SEC_TYPE 0402
J 0
(-4650 2050);
DISPLAY 1.021277 (-4650 2050);
PAINT ORANGE (-4650 2050);
DISPLAY INVISIBLE (-4650 2050);
FORCEPROP 2 LAST BOM_COST PROC_SIDEBAND
J 2
(-4600 1825);
PAINT MONO (-4600 1825);
DISPLAY INVISIBLE (-4600 1825);
FORCEPROP 2 LAST CDS_LIB mstr_discrete
J 0
(-4600 1825);
PAINT ORANGE (-4600 1825);
DISPLAY INVISIBLE (-4600 1825);
FORCEPROP 2 LAST SEC 1
J 0
(-4650 2050);
DISPLAY 0.680851 (-4650 2050);
PAINT MONO (-4650 2050);
DISPLAY INVISIBLE (-4650 2050);
FORCEPROP 2 LAST CDS_LOCATION R6D9
J 2
(-4645 1950);
DISPLAY 0.617021 (-4645 1950);
PAINT AQUA (-4645 1950);
DISPLAY INVISIBLE (-4645 1950);
FORCEPROP 1 LAST PATH I64
J 2
(-4650 2000);
DISPLAY 0.978723 (-4650 2000);
PAINT WHITE (-4650 2000);
DISPLAY INVISIBLE (-4650 2000);
FORCEPROP 2 LAST ROOM PROC_SIDEBAND
J 2
(-4625 1600);
PAINT ORANGE (-4625 1600);
DISPLAY INVISIBLE (-4625 1600);
FORCEADD RES..2
(-4275 1800);
FORCEPROP 1 LAST LOCATION R7P27
J 0
(-4230 1925);
DISPLAY 0.617021 (-4230 1925);
PAINT AQUA (-4230 1925);
FORCEPROP 1 LAST PART_NUMBER G21796-009
J 0
(-4235 1675);
DISPLAY 0.617021 (-4235 1675);
PAINT BLUE (-4235 1675);
FORCEPROP 1 LAST VALUE 150.0
J 0
(-4230 1875);
DISPLAY 0.617021 (-4230 1875);
PAINT SKYBLUE (-4230 1875);
FORCEPROP 1 LAST PACK_TYPE 0402
J 0
(-4235 1625);
DISPLAY 0.617021 (-4235 1625);
PAINT SKYBLUE (-4235 1625);
FORCEPROP 1 LAST MATERIAL CHIP
J 0
(-4235 1725);
DISPLAY 0.617021 (-4235 1725);
PAINT SKYBLUE (-4235 1725);
FORCEPROP 1 LAST WATTAGE 1/16W
J 0
(-4235 1775);
DISPLAY 0.617021 (-4235 1775);
PAINT SKYBLUE (-4235 1775);
FORCEPROP 1 LASTPIN (-4275 1700) $PN 2
J 0
(-4270 1710);
DISPLAY 0.617021 (-4270 1710);
PAINT ORANGE (-4270 1710);
FORCEPROP 1 LASTPIN (-4275 1900) $PN 1
J 0
(-4270 1862);
DISPLAY 0.617021 (-4270 1862);
PAINT ORANGE (-4270 1862);
FORCEPROP 1 LAST TOLERANCE 1%
J 0
(-4230 1825);
DISPLAY 0.617021 (-4230 1825);
PAINT SKYBLUE (-4230 1825);
FORCEPROP 2 LAST CDS_LIB mstr_discrete
J 0
(-4275 1800);
PAINT ORANGE (-4275 1800);
DISPLAY INVISIBLE (-4275 1800);
FORCEPROP 2 LAST BOM_COST PROC_SIDEBAND
J 0
(-4275 1800);
PAINT MONO (-4275 1800);
DISPLAY INVISIBLE (-4275 1800);
FORCEPROP 2 LAST SEC_TYPE 0402
J 0
(-4225 2025);
DISPLAY 1.021277 (-4225 2025);
PAINT ORANGE (-4225 2025);
DISPLAY INVISIBLE (-4225 2025);
FORCEPROP 2 LAST SEC 1
J 0
(-4225 2025);
DISPLAY 0.680851 (-4225 2025);
PAINT MONO (-4225 2025);
DISPLAY INVISIBLE (-4225 2025);
FORCEPROP 2 LAST CDS_LOCATION R7P27
J 0
(-4230 1925);
DISPLAY 0.617021 (-4230 1925);
PAINT AQUA (-4230 1925);
DISPLAY INVISIBLE (-4230 1925);
FORCEPROP 1 LAST PATH I65
J 0
(-4225 1975);
DISPLAY 0.978723 (-4225 1975);
PAINT WHITE (-4225 1975);
DISPLAY INVISIBLE (-4225 1975);
FORCEPROP 2 LAST ROOM PROC_SIDEBAND
J 0
(-4250 1575);
PAINT ORANGE (-4250 1575);
DISPLAY INVISIBLE (-4250 1575);
FORCEADD PVCCIO_CPU0..1
(-4600 2050);
FORCEPROP 3 LASTPIN (-4600 2000) SIG_NAME PVCCIO_CPU0\g
J 0
(-4590 2010);
DISPLAY 0.659574 (-4590 2010);
PAINT MONO (-4590 2010);
DISPLAY INVISIBLE (-4590 2010);
FORCEPROP 1 LAST VOLTAGE 1.1V
J 0
(-4645 2007);
DISPLAY 0.340426 (-4645 2007);
PAINT SKYBLUE (-4645 2007);
DISPLAY INVISIBLE (-4645 2007);
FORCEPROP 2 LAST CDS_LIB mstr_symbols
J 0
(-4600 2050);
PAINT ORANGE (-4600 2050);
DISPLAY INVISIBLE (-4600 2050);
FORCEPROP 1 LAST PATH I66
J 0
(-4550 2075);
DISPLAY 0.872340 (-4550 2075);
PAINT AQUA (-4550 2075);
DISPLAY INVISIBLE (-4550 2075);
FORCEPROP 1 LAST BODY_TYPE PLUMBING
J 0
(-4645 2007);
DISPLAY 0.340426 (-4645 2007);
PAINT GREEN (-4645 2007);
DISPLAY INVISIBLE (-4645 2007);
FORCEPROP 1 LAST HDL_POWER PVCCIO_CPU0
J 1
(-4600 2100);
DISPLAY 0.872340 (-4600 2100);
PAINT GREEN (-4600 2100);
DISPLAY INVISIBLE (-4600 2100);
FORCEADD RES..1
(-3725 1275);
FORCEPROP 1 LAST LOCATION R7D28
J 0
(-3775 1325);
DISPLAY 0.617021 (-3775 1325);
PAINT AQUA (-3775 1325);
FORCEPROP 1 LAST PART_NUMBER G21497-005
J 0
(-4100 1300);
DISPLAY 0.617021 (-4100 1300);
PAINT BLUE (-4100 1300);
FORCEPROP 1 LAST VALUE 0.0
J 2
(-3825 1225);
DISPLAY 0.617021 (-3825 1225);
PAINT SKYBLUE (-3825 1225);
FORCEPROP 1 LAST TOLERANCE 5%
J 0
(-3625 1175);
DISPLAY 0.617021 (-3625 1175);
PAINT SKYBLUE (-3625 1175);
FORCEPROP 1 LAST PACK_TYPE 0402
J 0
(-3850 1175);
DISPLAY 0.617021 (-3850 1175);
PAINT SKYBLUE (-3850 1175);
FORCEPROP 1 LAST MATERIAL CHIP
J 0
(-3750 1200);
DISPLAY 0.617021 (-3750 1200);
PAINT SKYBLUE (-3750 1200);
FORCEPROP 1 LAST WATTAGE 1/16W
J 2
(-3575 1225);
DISPLAY 0.617021 (-3575 1225);
PAINT SKYBLUE (-3575 1225);
FORCEPROP 1 LASTPIN (-3625 1275) $PN 2
J 0
(-3663 1287);
DISPLAY 0.617021 (-3663 1287);
PAINT ORANGE (-3663 1287);
FORCEPROP 1 LASTPIN (-3825 1275) $PN 1
J 0
(-3813 1287);
DISPLAY 0.617021 (-3813 1287);
PAINT ORANGE (-3813 1287);
FORCEPROP 2 LAST BOM_COST PROC_SIDEBAND
J 2
(-3725 1275);
PAINT MONO (-3725 1275);
DISPLAY INVISIBLE (-3725 1275);
FORCEPROP 2 LAST CDS_LIB mstr_discrete
J 0
(-3725 1275);
PAINT ORANGE (-3725 1275);
DISPLAY INVISIBLE (-3725 1275);
FORCEPROP 2 LAST SEC_TYPE 0402
J 0
(-3775 1475);
DISPLAY 1.021277 (-3775 1475);
PAINT ORANGE (-3775 1475);
DISPLAY INVISIBLE (-3775 1475);
FORCEPROP 2 LAST SEC 1
J 0
(-3775 1475);
DISPLAY 0.680851 (-3775 1475);
PAINT MONO (-3775 1475);
DISPLAY INVISIBLE (-3775 1475);
FORCEPROP 2 LAST CDS_LOCATION R7D28
J 0
(-3775 1325);
DISPLAY 0.617021 (-3775 1325);
PAINT AQUA (-3775 1325);
DISPLAY INVISIBLE (-3775 1325);
FORCEPROP 1 LAST PATH I67
J 0
(-3775 1425);
DISPLAY 0.978723 (-3775 1425);
PAINT WHITE (-3775 1425);
DISPLAY INVISIBLE (-3775 1425);
FORCEPROP 2 LAST ROOM PROC_SIDEBAND
J 0
(-3800 1200);
DISPLAY 0.617021 (-3800 1200);
PAINT ORANGE (-3800 1200);
DISPLAY INVISIBLE (-3800 1200);
FORCEADD RES..1
(-3775 1550);
FORCEPROP 1 LAST LOCATION R7D27
J 0
(-3825 1600);
DISPLAY 0.617021 (-3825 1600);
PAINT AQUA (-3825 1600);
FORCEPROP 1 LAST PART_NUMBER G21497-005
J 0
(-3900 1400);
DISPLAY 0.617021 (-3900 1400);
PAINT BLUE (-3900 1400);
FORCEPROP 1 LAST VALUE 0.0
J 2
(-3875 1500);
DISPLAY 0.617021 (-3875 1500);
PAINT SKYBLUE (-3875 1500);
FORCEPROP 1 LAST TOLERANCE 5%
J 0
(-3675 1450);
DISPLAY 0.617021 (-3675 1450);
PAINT SKYBLUE (-3675 1450);
FORCEPROP 1 LAST PACK_TYPE 0402
J 0
(-3900 1450);
DISPLAY 0.617021 (-3900 1450);
PAINT SKYBLUE (-3900 1450);
FORCEPROP 1 LAST MATERIAL CHIP
J 0
(-4050 1450);
DISPLAY 0.617021 (-4050 1450);
PAINT SKYBLUE (-4050 1450);
FORCEPROP 1 LAST WATTAGE 1/16W
J 2
(-3625 1500);
DISPLAY 0.617021 (-3625 1500);
PAINT SKYBLUE (-3625 1500);
FORCEPROP 1 LASTPIN (-3675 1550) $PN 2
J 0
(-3713 1562);
DISPLAY 0.617021 (-3713 1562);
PAINT ORANGE (-3713 1562);
FORCEPROP 1 LASTPIN (-3875 1550) $PN 1
J 0
(-3863 1562);
DISPLAY 0.617021 (-3863 1562);
PAINT ORANGE (-3863 1562);
FORCEPROP 2 LAST CDS_LIB mstr_discrete
J 0
(-3775 1550);
PAINT ORANGE (-3775 1550);
DISPLAY INVISIBLE (-3775 1550);
FORCEPROP 2 LAST SEC_TYPE 0402
J 0
(-3825 1750);
DISPLAY 1.021277 (-3825 1750);
PAINT ORANGE (-3825 1750);
DISPLAY INVISIBLE (-3825 1750);
FORCEPROP 2 LAST BOM_COST PROC_SIDEBAND
J 2
(-3775 1550);
PAINT MONO (-3775 1550);
DISPLAY INVISIBLE (-3775 1550);
FORCEPROP 2 LAST SEC 1
J 0
(-3825 1750);
DISPLAY 0.680851 (-3825 1750);
PAINT MONO (-3825 1750);
DISPLAY INVISIBLE (-3825 1750);
FORCEPROP 2 LAST CDS_LOCATION R7D27
J 0
(-3825 1600);
DISPLAY 0.617021 (-3825 1600);
PAINT AQUA (-3825 1600);
DISPLAY INVISIBLE (-3825 1600);
FORCEPROP 1 LAST PATH I68
J 0
(-3825 1700);
DISPLAY 0.978723 (-3825 1700);
PAINT WHITE (-3825 1700);
DISPLAY INVISIBLE (-3825 1700);
FORCEPROP 2 LAST ROOM PROC_SIDEBAND
J 0
(-3850 1475);
DISPLAY 0.617021 (-3850 1475);
PAINT ORANGE (-3850 1475);
DISPLAY INVISIBLE (-3850 1475);
FORCEADD OFFPAGE..5
R 2
(1075 1250);
FORCEPROP 2 LAST $XR3 247 
J 0
(1624 1250);
DISPLAY 0.638298 (1624 1250);
PAINT MONO (1624 1250);
FORCEPROP 2 LAST $XR2 190 
J 0
(1504 1250);
DISPLAY 0.638298 (1504 1250);
PAINT MONO (1504 1250);
FORCEPROP 2 LAST $XR1 120 
J 0
(1384 1250);
DISPLAY 0.638298 (1384 1250);
PAINT MONO (1384 1250);
FORCEPROP 2 LAST $XR0 147 
J 0
(1264 1250);
DISPLAY 0.638298 (1264 1250);
PAINT MONO (1264 1250);
FORCEPROP 2 LAST CDS_LIB mstr_standard
J 0
(1075 1250);
PAINT ORANGE (1075 1250);
DISPLAY INVISIBLE (1075 1250);
FORCEPROP 2 LAST PATH I69
J 0
(1275 1300);
DISPLAY 1.021277 (1275 1300);
PAINT ORANGE (1275 1300);
DISPLAY INVISIBLE (1275 1300);
FORCEPROP 1 LAST OFFPAGE TRUE
J 2
(750 1125);
PAINT GREEN (750 1125);
DISPLAY INVISIBLE (750 1125);
FORCEPROP 1 LAST COMMENT_BODY TRUE
J 2
(975 1175);
DISPLAY 1.170213 (975 1175);
PAINT GREEN (975 1175);
DISPLAY INVISIBLE (975 1175);
FORCEADD RES..1
(-100 1250);
FORCEPROP 1 LAST LOCATION R7D25
J 0
(-150 1300);
DISPLAY 0.617021 (-150 1300);
PAINT AQUA (-150 1300);
FORCEPROP 1 LAST PART_NUMBER G21796-074
J 0
(-25 1150);
DISPLAY 0.617021 (-25 1150);
PAINT BLUE (-25 1150);
FORCEPROP 1 LAST VALUE 33.2
J 2
(-125 1200);
DISPLAY 0.617021 (-125 1200);
PAINT SKYBLUE (-125 1200);
FORCEPROP 1 LAST TOLERANCE 1%
J 0
(-100 1200);
DISPLAY 0.617021 (-100 1200);
PAINT SKYBLUE (-100 1200);
FORCEPROP 1 LAST PACK_TYPE 0402
J 0
(0 1200);
DISPLAY 0.617021 (0 1200);
PAINT SKYBLUE (0 1200);
FORCEPROP 1 LAST MATERIAL CHIP
J 0
(-175 1150);
DISPLAY 0.617021 (-175 1150);
PAINT SKYBLUE (-175 1150);
FORCEPROP 1 LAST WATTAGE 1/16W
J 2
(-200 1150);
DISPLAY 0.617021 (-200 1150);
PAINT SKYBLUE (-200 1150);
FORCEPROP 1 LASTPIN (0 1250) $PN 2
J 0
(-38 1262);
DISPLAY 0.617021 (-38 1262);
PAINT ORANGE (-38 1262);
FORCEPROP 1 LASTPIN (-200 1250) $PN 1
J 0
(-188 1262);
DISPLAY 0.617021 (-188 1262);
PAINT ORANGE (-188 1262);
FORCEPROP 2 LAST SEC_TYPE 0402
J 0
(-150 1450);
DISPLAY 1.021277 (-150 1450);
PAINT ORANGE (-150 1450);
DISPLAY INVISIBLE (-150 1450);
FORCEPROP 2 LAST BOM_COST PROC_SIDEBAND
J 2
(-100 1250);
PAINT MONO (-100 1250);
DISPLAY INVISIBLE (-100 1250);
FORCEPROP 2 LAST CDS_LIB mstr_discrete
J 0
(-100 1250);
PAINT ORANGE (-100 1250);
DISPLAY INVISIBLE (-100 1250);
FORCEPROP 2 LAST SEC 1
J 0
(-150 1450);
DISPLAY 0.680851 (-150 1450);
PAINT MONO (-150 1450);
DISPLAY INVISIBLE (-150 1450);
FORCEPROP 2 LAST CDS_LOCATION R7D25
J 0
(-150 1300);
DISPLAY 0.617021 (-150 1300);
PAINT AQUA (-150 1300);
DISPLAY INVISIBLE (-150 1300);
FORCEPROP 1 LAST PATH I70
J 0
(-150 1400);
DISPLAY 0.978723 (-150 1400);
PAINT WHITE (-150 1400);
DISPLAY INVISIBLE (-150 1400);
FORCEPROP 2 LAST ROOM PROC_SIDEBAND
J 0
(-175 1175);
DISPLAY 0.617021 (-175 1175);
PAINT ORANGE (-175 1175);
DISPLAY INVISIBLE (-175 1175);
FORCEADD RES..2
(-2925 3900);
FORCEPROP 1 LAST LOCATION R3R2
J 0
(-2880 4025);
DISPLAY 0.617021 (-2880 4025);
PAINT AQUA (-2880 4025);
FORCEPROP 1 LAST PART_NUMBER G21796-026
J 0
(-2885 3775);
DISPLAY 0.617021 (-2885 3775);
PAINT BLUE (-2885 3775);
FORCEPROP 1 LAST VALUE 1.00K
J 0
(-2880 3975);
DISPLAY 0.617021 (-2880 3975);
PAINT SKYBLUE (-2880 3975);
FORCEPROP 1 LAST TOLERANCE 1%
J 0
(-2880 3925);
DISPLAY 0.617021 (-2880 3925);
PAINT SKYBLUE (-2880 3925);
FORCEPROP 1 LAST PACK_TYPE 0402
J 0
(-2885 3725);
DISPLAY 0.617021 (-2885 3725);
PAINT SKYBLUE (-2885 3725);
FORCEPROP 1 LAST MATERIAL CHIP
J 0
(-2885 3825);
DISPLAY 0.617021 (-2885 3825);
PAINT SKYBLUE (-2885 3825);
FORCEPROP 1 LAST WATTAGE 1/16W
J 0
(-2885 3875);
DISPLAY 0.617021 (-2885 3875);
PAINT SKYBLUE (-2885 3875);
FORCEPROP 1 LASTPIN (-2925 3800) $PN 2
J 0
(-2920 3810);
DISPLAY 0.617021 (-2920 3810);
PAINT ORANGE (-2920 3810);
FORCEPROP 1 LASTPIN (-2925 4000) $PN 1
J 0
(-2920 3962);
DISPLAY 0.617021 (-2920 3962);
PAINT ORANGE (-2920 3962);
FORCEPROP 1 LAST PATH I75
J 0
(-2875 4075);
DISPLAY 0.978723 (-2875 4075);
PAINT WHITE (-2875 4075);
DISPLAY INVISIBLE (-2875 4075);
FORCEPROP 0 LAST ROOM PROC_SIDEBAND
J 0
(-2875 4125);
DISPLAY 1.021277 (-2875 4125);
PAINT ORANGE (-2875 4125);
DISPLAY INVISIBLE (-2875 4125);
FORCEPROP 2 LAST SEC_TYPE 0402
J 0
(-2875 4125);
DISPLAY 1.021277 (-2875 4125);
PAINT ORANGE (-2875 4125);
DISPLAY INVISIBLE (-2875 4125);
FORCEPROP 2 LAST SEC 1
J 0
(-2875 4125);
DISPLAY 0.680851 (-2875 4125);
PAINT MONO (-2875 4125);
DISPLAY INVISIBLE (-2875 4125);
FORCEPROP 2 LAST CDS_LIB mstr_discrete
J 0
(-2925 3900);
PAINT MONO (-2925 3900);
DISPLAY INVISIBLE (-2925 3900);
FORCEPROP 2 LAST CDS_LOCATION R3R2
J 0
(-2880 4025);
DISPLAY 0.617021 (-2880 4025);
PAINT AQUA (-2880 4025);
DISPLAY INVISIBLE (-2880 4025);
FORCEADD GND..1
(-2925 3650);
FORCEPROP 3 LASTPIN (-2925 3700) SIG_NAME GND\g
J 0
(-2915 3710);
DISPLAY 0.659574 (-2915 3710);
PAINT MONO (-2915 3710);
DISPLAY INVISIBLE (-2915 3710);
FORCEPROP 1 LAST VOLTAGE 0
J 0
(-2925 3650);
PAINT SKYBLUE (-2925 3650);
DISPLAY INVISIBLE (-2925 3650);
FORCEPROP 1 LAST SIZE 1B
J 0
(-2850 3600);
DISPLAY 1.212766 (-2850 3600);
PAINT GREEN (-2850 3600);
DISPLAY INVISIBLE (-2850 3600);
FORCEPROP 2 LAST CDS_LIB mstr_symbols
J 0
(-2925 3650);
PAINT MONO (-2925 3650);
DISPLAY INVISIBLE (-2925 3650);
FORCEPROP 1 LAST PATH I76
J 0
(-2850 3650);
DISPLAY 0.872340 (-2850 3650);
PAINT AQUA (-2850 3650);
DISPLAY INVISIBLE (-2850 3650);
FORCEPROP 1 LAST BODY_TYPE PLUMBING
J 0
(-2970 3607);
DISPLAY 0.340426 (-2970 3607);
PAINT GREEN (-2970 3607);
DISPLAY INVISIBLE (-2970 3607);
FORCEPROP 1 LAST HDL_POWER GND
J 0
(-2925 3800);
DISPLAY 1.212766 (-2925 3800);
PAINT GREEN (-2925 3800);
DISPLAY INVISIBLE (-2925 3800);
FORCEADD CAP..1
(-900 2525);
FORCEPROP 1 LASTPIN (-900 2625) $PN 1
J 0
(-890 2605);
DISPLAY 0.617021 (-890 2605);
PAINT ORANGE (-890 2605);
FORCEPROP 1 LAST VALUE 1.0UF
J 0
(-850 2575);
DISPLAY 0.617021 (-850 2575);
PAINT SKYBLUE (-850 2575);
FORCEPROP 1 LAST VOLTAGE 16V
J 0
(-850 2525);
DISPLAY 0.617021 (-850 2525);
PAINT SKYBLUE (-850 2525);
FORCEPROP 1 LAST TOLERANCE 10%
J 0
(-850 2475);
DISPLAY 0.617021 (-850 2475);
PAINT SKYBLUE (-850 2475);
FORCEPROP 1 LAST LOCATION C7D4
J 0
(-850 2625);
DISPLAY 0.617021 (-850 2625);
PAINT AQUA (-850 2625);
FORCEPROP 1 LAST PACK_TYPE 0402
J 0
(-850 2325);
DISPLAY 0.617021 (-850 2325);
PAINT SKYBLUE (-850 2325);
FORCEPROP 1 LASTPIN (-900 2425) $PN 2
J 0
(-890 2405);
DISPLAY 0.617021 (-890 2405);
PAINT ORANGE (-890 2405);
FORCEPROP 1 LAST PART_NUMBER D97712-011
J 0
(-850 2375);
DISPLAY 0.617021 (-850 2375);
PAINT BLUE (-850 2375);
FORCEPROP 1 LAST MATERIAL X6S
J 0
(-850 2425);
DISPLAY 0.617021 (-850 2425);
PAINT SKYBLUE (-850 2425);
FORCEPROP 2 LAST CDS_LIB mstr_discrete
J 0
(-900 2525);
PAINT ORANGE (-900 2525);
DISPLAY INVISIBLE (-900 2525);
FORCEPROP 2 LAST SEC_TYPE 0402
J 0
(-850 2725);
DISPLAY 1.021277 (-850 2725);
PAINT ORANGE (-850 2725);
DISPLAY INVISIBLE (-850 2725);
FORCEPROP 0 LAST BOM_COST PROC
J 0
(-850 2725);
DISPLAY 1.021277 (-850 2725);
PAINT ORANGE (-850 2725);
DISPLAY INVISIBLE (-850 2725);
FORCEPROP 2 LAST SEC 1
J 0
(-850 2725);
DISPLAY 0.680851 (-850 2725);
PAINT MONO (-850 2725);
DISPLAY INVISIBLE (-850 2725);
FORCEPROP 2 LAST CDS_LOCATION C7D4
J 0
(-850 2625);
DISPLAY 0.617021 (-850 2625);
PAINT AQUA (-850 2625);
DISPLAY INVISIBLE (-850 2625);
FORCEPROP 1 LAST PATH I79
J 0
(-850 2675);
DISPLAY 0.978723 (-850 2675);
PAINT WHITE (-850 2675);
DISPLAY INVISIBLE (-850 2675);
FORCEPROP 0 LAST ROOM PROC_SIDEBAND
J 0
(-850 2725);
DISPLAY 1.021277 (-850 2725);
PAINT ORANGE (-850 2725);
DISPLAY INVISIBLE (-850 2725);
FORCEADD GND..1
(-900 2350);
FORCEPROP 3 LASTPIN (-900 2400) SIG_NAME GND\g
J 0
(-890 2410);
DISPLAY 0.659574 (-890 2410);
PAINT MONO (-890 2410);
DISPLAY INVISIBLE (-890 2410);
FORCEPROP 1 LAST VOLTAGE 0
J 0
(-900 2350);
PAINT SKYBLUE (-900 2350);
DISPLAY INVISIBLE (-900 2350);
FORCEPROP 2 LAST CDS_LIB mstr_symbols
J 0
(-900 2350);
PAINT ORANGE (-900 2350);
DISPLAY INVISIBLE (-900 2350);
FORCEPROP 1 LAST SIZE 1B
J 0
(-825 2300);
DISPLAY 1.212766 (-825 2300);
PAINT GREEN (-825 2300);
DISPLAY INVISIBLE (-825 2300);
FORCEPROP 1 LAST PATH I80
J 0
(-825 2350);
DISPLAY 0.872340 (-825 2350);
PAINT AQUA (-825 2350);
DISPLAY INVISIBLE (-825 2350);
FORCEPROP 1 LAST BODY_TYPE PLUMBING
J 0
(-945 2307);
DISPLAY 0.340426 (-945 2307);
PAINT GREEN (-945 2307);
DISPLAY INVISIBLE (-945 2307);
FORCEPROP 1 LAST HDL_POWER GND
J 0
(-900 2500);
DISPLAY 1.212766 (-900 2500);
PAINT GREEN (-900 2500);
DISPLAY INVISIBLE (-900 2500);
FORCEADD PVCCIO_CPU0..1
(-2850 2700);
FORCEPROP 3 LASTPIN (-2850 2650) SIG_NAME PVCCIO_CPU0\g
J 0
(-2840 2660);
DISPLAY 0.659574 (-2840 2660);
PAINT MONO (-2840 2660);
DISPLAY INVISIBLE (-2840 2660);
FORCEPROP 1 LAST PATH I82
J 0
(-2800 2725);
DISPLAY 0.872340 (-2800 2725);
PAINT AQUA (-2800 2725);
DISPLAY INVISIBLE (-2800 2725);
FORCEPROP 2 LAST CDS_LIB mstr_symbols
J 0
(-2850 2700);
PAINT ORANGE (-2850 2700);
DISPLAY INVISIBLE (-2850 2700);
FORCEPROP 1 LAST VOLTAGE 1.1V
J 0
(-2895 2657);
DISPLAY 0.340426 (-2895 2657);
PAINT SKYBLUE (-2895 2657);
DISPLAY INVISIBLE (-2895 2657);
FORCEPROP 1 LAST BODY_TYPE PLUMBING
J 0
(-2895 2657);
DISPLAY 0.340426 (-2895 2657);
PAINT GREEN (-2895 2657);
DISPLAY INVISIBLE (-2895 2657);
FORCEPROP 1 LAST HDL_POWER PVCCIO_CPU0
J 1
(-2850 2750);
DISPLAY 0.872340 (-2850 2750);
PAINT GREEN (-2850 2750);
DISPLAY INVISIBLE (-2850 2750);
FORCEADD CAP..1
(-1025 4725);
FORCEPROP 1 LAST PART_NUMBER D97712-011
J 0
(-975 4575);
DISPLAY 0.617021 (-975 4575);
PAINT BLUE (-975 4575);
FORCEPROP 1 LAST MATERIAL X6S
J 0
(-975 4625);
DISPLAY 0.617021 (-975 4625);
PAINT SKYBLUE (-975 4625);
FORCEPROP 1 LAST TOLERANCE 10%
J 0
(-975 4675);
DISPLAY 0.617021 (-975 4675);
PAINT SKYBLUE (-975 4675);
FORCEPROP 1 LAST VOLTAGE 16V
J 0
(-975 4725);
DISPLAY 0.617021 (-975 4725);
PAINT SKYBLUE (-975 4725);
FORCEPROP 1 LAST VALUE 1.0UF
J 0
(-975 4775);
DISPLAY 0.617021 (-975 4775);
PAINT SKYBLUE (-975 4775);
FORCEPROP 1 LAST LOCATION C3P50
J 0
(-975 4825);
DISPLAY 0.617021 (-975 4825);
PAINT AQUA (-975 4825);
FORCEPROP 1 LASTPIN (-1025 4625) $PN 2
J 0
(-1015 4605);
DISPLAY 0.617021 (-1015 4605);
PAINT ORANGE (-1015 4605);
FORCEPROP 1 LASTPIN (-1025 4825) $PN 1
J 0
(-1015 4805);
DISPLAY 0.617021 (-1015 4805);
PAINT ORANGE (-1015 4805);
FORCEPROP 1 LAST PACK_TYPE 0402
J 0
(-975 4525);
DISPLAY 0.617021 (-975 4525);
PAINT SKYBLUE (-975 4525);
FORCEPROP 2 LAST SEC_TYPE 0402
J 0
(-975 4925);
DISPLAY 1.021277 (-975 4925);
PAINT ORANGE (-975 4925);
DISPLAY INVISIBLE (-975 4925);
FORCEPROP 2 LAST CDS_LIB mstr_discrete
J 0
(-1025 4725);
PAINT ORANGE (-1025 4725);
DISPLAY INVISIBLE (-1025 4725);
FORCEPROP 0 LAST BOM_COST PROC
J 0
(-975 4925);
DISPLAY 1.021277 (-975 4925);
PAINT ORANGE (-975 4925);
DISPLAY INVISIBLE (-975 4925);
FORCEPROP 2 LAST SEC 1
J 0
(-975 4925);
DISPLAY 0.680851 (-975 4925);
PAINT MONO (-975 4925);
DISPLAY INVISIBLE (-975 4925);
FORCEPROP 2 LAST CDS_LOCATION C3P50
J 0
(-975 4825);
DISPLAY 0.617021 (-975 4825);
PAINT AQUA (-975 4825);
DISPLAY INVISIBLE (-975 4825);
FORCEPROP 1 LAST PATH I84
J 0
(-975 4875);
DISPLAY 0.978723 (-975 4875);
PAINT WHITE (-975 4875);
DISPLAY INVISIBLE (-975 4875);
FORCEPROP 0 LAST ROOM PROC_SIDEBAND
J 0
(-975 4925);
DISPLAY 1.021277 (-975 4925);
PAINT ORANGE (-975 4925);
DISPLAY INVISIBLE (-975 4925);
FORCEADD GND..1
(-1025 4550);
FORCEPROP 3 LASTPIN (-1025 4600) SIG_NAME GND\g
J 0
(-1015 4610);
DISPLAY 0.659574 (-1015 4610);
PAINT MONO (-1015 4610);
DISPLAY INVISIBLE (-1015 4610);
FORCEPROP 1 LAST VOLTAGE 0
J 0
(-1025 4550);
PAINT SKYBLUE (-1025 4550);
DISPLAY INVISIBLE (-1025 4550);
FORCEPROP 1 LAST SIZE 1B
J 0
(-950 4500);
DISPLAY 1.212766 (-950 4500);
PAINT GREEN (-950 4500);
DISPLAY INVISIBLE (-950 4500);
FORCEPROP 2 LAST CDS_LIB mstr_symbols
J 0
(-1025 4550);
PAINT ORANGE (-1025 4550);
DISPLAY INVISIBLE (-1025 4550);
FORCEPROP 1 LAST PATH I85
J 0
(-950 4550);
DISPLAY 0.872340 (-950 4550);
PAINT AQUA (-950 4550);
DISPLAY INVISIBLE (-950 4550);
FORCEPROP 1 LAST BODY_TYPE PLUMBING
J 0
(-1070 4507);
DISPLAY 0.340426 (-1070 4507);
PAINT GREEN (-1070 4507);
DISPLAY INVISIBLE (-1070 4507);
FORCEPROP 1 LAST HDL_POWER GND
J 0
(-1025 4700);
DISPLAY 1.212766 (-1025 4700);
PAINT GREEN (-1025 4700);
DISPLAY INVISIBLE (-1025 4700);
FORCEADD OFFPAGE..2
(1050 4000);
FORCEPROP 2 LAST $XR2 247 
J 0
(1479 4000);
DISPLAY 0.638298 (1479 4000);
PAINT MONO (1479 4000);
FORCEPROP 2 LAST $XR1 190 
J 0
(1359 4000);
DISPLAY 0.638298 (1359 4000);
PAINT MONO (1359 4000);
FORCEPROP 2 LAST $XR0 144 
J 0
(1239 4000);
DISPLAY 0.638298 (1239 4000);
PAINT MONO (1239 4000);
FORCEPROP 2 LAST CDS_LIB mstr_standard
J 0
(1050 4000);
PAINT MONO (1050 4000);
DISPLAY INVISIBLE (1050 4000);
FORCEPROP 2 LAST PATH I88
J 0
(1375 4050);
DISPLAY 1.021277 (1375 4050);
PAINT ORANGE (1375 4050);
DISPLAY INVISIBLE (1375 4050);
FORCEPROP 1 LAST OFFPAGE TRUE
J 0
(1375 3875);
PAINT GREEN (1375 3875);
DISPLAY INVISIBLE (1375 3875);
FORCEPROP 1 LAST COMMENT_BODY TRUE
J 0
(1005 3905);
DISPLAY 1.085106 (1005 3905);
PAINT GREEN (1005 3905);
DISPLAY INVISIBLE (1005 3905);
FORCEADD OFFPAGE..5
R 2
(1075 1800);
FORCEPROP 2 LAST $XR1 144 
J 0
(1384 1800);
DISPLAY 0.638298 (1384 1800);
PAINT MONO (1384 1800);
FORCEPROP 2 LAST $XR0 120 
J 0
(1264 1800);
DISPLAY 0.638298 (1264 1800);
PAINT MONO (1264 1800);
FORCEPROP 2 LAST CDS_LIB mstr_standard
J 0
(1075 1800);
PAINT ORANGE (1075 1800);
DISPLAY INVISIBLE (1075 1800);
FORCEPROP 2 LAST PATH I89
J 0
(1400 1850);
DISPLAY 1.021277 (1400 1850);
PAINT ORANGE (1400 1850);
DISPLAY INVISIBLE (1400 1850);
FORCEPROP 1 LAST OFFPAGE TRUE
J 2
(750 1675);
PAINT GREEN (750 1675);
DISPLAY INVISIBLE (750 1675);
FORCEPROP 1 LAST COMMENT_BODY TRUE
J 2
(975 1725);
DISPLAY 1.170213 (975 1725);
PAINT GREEN (975 1725);
DISPLAY INVISIBLE (975 1725);
FORCEADD RES..2
(-2900 4525);
FORCEPROP 1 LAST PACK_TYPE 0402
J 0
(-2860 4350);
DISPLAY 0.617021 (-2860 4350);
PAINT SKYBLUE (-2860 4350);
FORCEPROP 1 LAST LOCATION R3P41
J 0
(-2855 4650);
DISPLAY 0.617021 (-2855 4650);
PAINT AQUA (-2855 4650);
FORCEPROP 1 LAST TOLERANCE 1.0%
J 0
(-2855 4550);
DISPLAY 0.617021 (-2855 4550);
PAINT SKYBLUE (-2855 4550);
FORCEPROP 1 LASTPIN (-2900 4425) $PN 2
J 0
(-2895 4435);
DISPLAY 0.617021 (-2895 4435);
PAINT ORANGE (-2895 4435);
FORCEPROP 1 LASTPIN (-2900 4625) $PN 1
J 0
(-2895 4587);
DISPLAY 0.617021 (-2895 4587);
PAINT ORANGE (-2895 4587);
FORCEPROP 1 LAST PART_NUMBER G21796-267
J 0
(-2860 4400);
DISPLAY 0.617021 (-2860 4400);
PAINT BLUE (-2860 4400);
FORCEPROP 1 LAST MATERIAL CHIP
J 0
(-2860 4450);
DISPLAY 0.617021 (-2860 4450);
PAINT SKYBLUE (-2860 4450);
FORCEPROP 1 LAST WATTAGE 1/16W
J 0
(-2860 4500);
DISPLAY 0.617021 (-2860 4500);
PAINT SKYBLUE (-2860 4500);
FORCEPROP 1 LAST VALUE 75
J 0
(-2855 4600);
DISPLAY 0.617021 (-2855 4600);
PAINT SKYBLUE (-2855 4600);
FORCEPROP 2 LAST CDS_LIB mstr_discrete
J 0
(-2900 4525);
PAINT ORANGE (-2900 4525);
DISPLAY INVISIBLE (-2900 4525);
FORCEPROP 2 LAST BOM_COST PROC_SIDEBAND
J 0
(-2900 4525);
PAINT MONO (-2900 4525);
DISPLAY INVISIBLE (-2900 4525);
FORCEPROP 2 LAST SEC_TYPE 0402
J 0
(-2850 4750);
DISPLAY 1.021277 (-2850 4750);
PAINT ORANGE (-2850 4750);
DISPLAY INVISIBLE (-2850 4750);
FORCEPROP 2 LAST SEC 1
J 0
(-2850 4750);
DISPLAY 0.680851 (-2850 4750);
PAINT MONO (-2850 4750);
DISPLAY INVISIBLE (-2850 4750);
FORCEPROP 2 LAST CDS_LOCATION R3P41
J 0
(-2855 4650);
DISPLAY 0.617021 (-2855 4650);
PAINT AQUA (-2855 4650);
DISPLAY INVISIBLE (-2855 4650);
FORCEPROP 1 LAST PATH I9
J 0
(-2850 4700);
DISPLAY 0.978723 (-2850 4700);
PAINT WHITE (-2850 4700);
DISPLAY INVISIBLE (-2850 4700);
FORCEPROP 2 LAST ROOM PROC_SIDEBAND
J 0
(-2875 4300);
PAINT ORANGE (-2875 4300);
DISPLAY INVISIBLE (-2875 4300);
FORCEADD OFFPAGE..1
(-5350 2800);
FORCEPROP 2 LAST $XR0 21 
J 0
(-5571 2800);
DISPLAY 0.638298 (-5571 2800);
PAINT MONO (-5571 2800);
FORCEPROP 2 LAST PATH I90
J 0
(-5550 2850);
DISPLAY 1.021277 (-5550 2850);
PAINT ORANGE (-5550 2850);
DISPLAY INVISIBLE (-5550 2850);
FORCEPROP 2 LAST CDS_LIB mstr_standard
J 0
(-5350 2800);
PAINT ORANGE (-5350 2800);
DISPLAY INVISIBLE (-5350 2800);
FORCEPROP 1 LAST OFFPAGE TRUE
J 0
(-5025 2675);
PAINT GREEN (-5025 2675);
DISPLAY INVISIBLE (-5025 2675);
FORCEPROP 1 LAST COMMENT_BODY TRUE
J 0
(-5225 2700);
DISPLAY 1.170213 (-5225 2700);
PAINT GREEN (-5225 2700);
DISPLAY INVISIBLE (-5225 2700);
FORCEADD OFFPAGE..1
(-5350 2550);
FORCEPROP 2 LAST $XR0 55 
J 0
(-5571 2550);
DISPLAY 0.638298 (-5571 2550);
PAINT MONO (-5571 2550);
FORCEPROP 2 LAST PATH I91
J 0
(-5550 2600);
DISPLAY 1.021277 (-5550 2600);
PAINT ORANGE (-5550 2600);
DISPLAY INVISIBLE (-5550 2600);
FORCEPROP 2 LAST CDS_LIB mstr_standard
J 0
(-5350 2550);
PAINT ORANGE (-5350 2550);
DISPLAY INVISIBLE (-5350 2550);
FORCEPROP 1 LAST OFFPAGE TRUE
J 0
(-5025 2425);
PAINT GREEN (-5025 2425);
DISPLAY INVISIBLE (-5025 2425);
FORCEPROP 1 LAST COMMENT_BODY TRUE
J 0
(-5225 2450);
DISPLAY 1.170213 (-5225 2450);
PAINT GREEN (-5225 2450);
DISPLAY INVISIBLE (-5225 2450);
FORCEADD RES..1
(-4725 2550);
FORCEPROP 1 LAST MATERIAL CHIP
J 0
(-4825 2450);
DISPLAY 0.617021 (-4825 2450);
PAINT SKYBLUE (-4825 2450);
FORCEPROP 1 LAST PACK_TYPE 0402
J 0
(-4700 2450);
DISPLAY 0.617021 (-4700 2450);
PAINT SKYBLUE (-4700 2450);
FORCEPROP 1 LAST PART_NUMBER G21497-005
J 0
(-4875 2400);
DISPLAY 0.617021 (-4875 2400);
PAINT BLUE (-4875 2400);
FORCEPROP 1 LASTPIN (-4825 2550) $PN 1
J 0
(-4813 2562);
DISPLAY 0.617021 (-4813 2562);
PAINT ORANGE (-4813 2562);
FORCEPROP 1 LAST WATTAGE 1/16W
J 2
(-4625 2500);
DISPLAY 0.617021 (-4625 2500);
PAINT SKYBLUE (-4625 2500);
FORCEPROP 1 LAST TOLERANCE 5%
J 0
(-4825 2500);
DISPLAY 0.617021 (-4825 2500);
PAINT SKYBLUE (-4825 2500);
FORCEPROP 1 LAST VALUE 0.0
J 2
(-4850 2500);
DISPLAY 0.617021 (-4850 2500);
PAINT SKYBLUE (-4850 2500);
FORCEPROP 1 LAST LOCATION R2T44
J 0
(-4775 2600);
DISPLAY 0.617021 (-4775 2600);
PAINT AQUA (-4775 2600);
FORCEPROP 1 LASTPIN (-4625 2550) $PN 2
J 0
(-4663 2562);
DISPLAY 0.617021 (-4663 2562);
PAINT ORANGE (-4663 2562);
FORCEPROP 2 LAST ROOM PROC_SIDEBAND
J 0
(-4800 2475);
DISPLAY 0.617021 (-4800 2475);
PAINT ORANGE (-4800 2475);
DISPLAY INVISIBLE (-4800 2475);
FORCEPROP 1 LAST PATH I92
J 0
(-4775 2700);
DISPLAY 0.978723 (-4775 2700);
PAINT WHITE (-4775 2700);
DISPLAY INVISIBLE (-4775 2700);
FORCEPROP 2 LAST CDS_LOCATION R2T44
J 0
(-4775 2600);
DISPLAY 0.617021 (-4775 2600);
PAINT AQUA (-4775 2600);
DISPLAY INVISIBLE (-4775 2600);
FORCEPROP 2 LAST $SEC 1
J 0
(-4775 2750);
DISPLAY 0.680851 (-4775 2750);
PAINT MONO (-4775 2750);
DISPLAY INVISIBLE (-4775 2750);
FORCEPROP 2 LAST CDS_SEC 1
J 0
(-4775 2750);
DISPLAY 1.021277 (-4775 2750);
PAINT ORANGE (-4775 2750);
DISPLAY INVISIBLE (-4775 2750);
FORCEPROP 2 LAST CDS_LIB mstr_discrete
J 0
(-4725 2550);
PAINT ORANGE (-4725 2550);
DISPLAY INVISIBLE (-4725 2550);
FORCEPROP 2 LAST BOM_COST PROC
J 2
(-4725 2550);
PAINT MONO (-4725 2550);
DISPLAY INVISIBLE (-4725 2550);
FORCEADD RES..1
(-4750 2800);
FORCEPROP 1 LASTPIN (-4850 2800) $PN 1
J 0
(-4838 2812);
DISPLAY 0.617021 (-4838 2812);
PAINT ORANGE (-4838 2812);
FORCEPROP 1 LASTPIN (-4650 2800) $PN 2
J 0
(-4688 2812);
DISPLAY 0.617021 (-4688 2812);
PAINT ORANGE (-4688 2812);
FORCEPROP 1 LAST WATTAGE 1/16W
J 2
(-4625 2750);
DISPLAY 0.617021 (-4625 2750);
PAINT SKYBLUE (-4625 2750);
FORCEPROP 1 LAST MATERIAL CHIP
J 0
(-4825 2700);
DISPLAY 0.617021 (-4825 2700);
PAINT SKYBLUE (-4825 2700);
FORCEPROP 1 LAST TOLERANCE 5%
J 0
(-4825 2750);
DISPLAY 0.617021 (-4825 2750);
PAINT SKYBLUE (-4825 2750);
FORCEPROP 1 LAST VALUE 0.0
J 2
(-4850 2750);
DISPLAY 0.617021 (-4850 2750);
PAINT SKYBLUE (-4850 2750);
FORCEPROP 1 LAST LOCATION R2T40
J 0
(-4800 2850);
DISPLAY 0.617021 (-4800 2850);
PAINT AQUA (-4800 2850);
FORCEPROP 1 LAST PART_NUMBER G21497-005
J 0
(-4875 2650);
DISPLAY 0.617021 (-4875 2650);
PAINT BLUE (-4875 2650);
FORCEPROP 1 LAST PACK_TYPE 0402
J 0
(-4700 2700);
DISPLAY 0.617021 (-4700 2700);
PAINT SKYBLUE (-4700 2700);
FORCEPROP 2 LAST ROOM PROC_SIDEBAND
J 0
(-4825 2725);
DISPLAY 0.617021 (-4825 2725);
PAINT ORANGE (-4825 2725);
DISPLAY INVISIBLE (-4825 2725);
FORCEPROP 1 LAST PATH I93
J 0
(-4800 2950);
DISPLAY 0.978723 (-4800 2950);
PAINT WHITE (-4800 2950);
DISPLAY INVISIBLE (-4800 2950);
FORCEPROP 2 LAST CDS_LOCATION R2T40
J 0
(-4800 2850);
DISPLAY 0.617021 (-4800 2850);
PAINT AQUA (-4800 2850);
DISPLAY INVISIBLE (-4800 2850);
FORCEPROP 2 LAST $SEC 1
J 0
(-4800 3000);
DISPLAY 0.680851 (-4800 3000);
PAINT MONO (-4800 3000);
DISPLAY INVISIBLE (-4800 3000);
FORCEPROP 2 LAST CDS_SEC 1
J 0
(-4800 3000);
DISPLAY 1.021277 (-4800 3000);
PAINT ORANGE (-4800 3000);
DISPLAY INVISIBLE (-4800 3000);
FORCEPROP 2 LAST CDS_LIB mstr_discrete
J 0
(-4750 2800);
PAINT ORANGE (-4750 2800);
DISPLAY INVISIBLE (-4750 2800);
FORCEPROP 2 LAST BOM_COST PROC
J 2
(-4750 2800);
PAINT MONO (-4750 2800);
DISPLAY INVISIBLE (-4750 2800);
FORCEADD RES..2
(-4000 2950);
FORCEPROP 1 LAST TOLERANCE 1%
J 0
(-3955 2975);
DISPLAY 0.617021 (-3955 2975);
PAINT SKYBLUE (-3955 2975);
FORCEPROP 1 LAST PACK_TYPE 0402
J 0
(-3960 2775);
DISPLAY 0.617021 (-3960 2775);
PAINT SKYBLUE (-3960 2775);
FORCEPROP 1 LAST LOCATION R2T37
J 0
(-3955 3075);
DISPLAY 0.617021 (-3955 3075);
PAINT AQUA (-3955 3075);
FORCEPROP 1 LAST VALUE 200.0
J 0
(-3955 3025);
DISPLAY 0.617021 (-3955 3025);
PAINT SKYBLUE (-3955 3025);
FORCEPROP 1 LAST PART_NUMBER G21796-004
J 0
(-3960 2825);
DISPLAY 0.617021 (-3960 2825);
PAINT BLUE (-3960 2825);
FORCEPROP 1 LAST MATERIAL CHIP
J 0
(-3960 2875);
DISPLAY 0.617021 (-3960 2875);
PAINT SKYBLUE (-3960 2875);
FORCEPROP 1 LAST WATTAGE 1/16W
J 0
(-3960 2925);
DISPLAY 0.617021 (-3960 2925);
PAINT SKYBLUE (-3960 2925);
FORCEPROP 2 LAST CDS_LIB mstr_discrete
J 0
(-4000 2950);
PAINT ORANGE (-4000 2950);
DISPLAY INVISIBLE (-4000 2950);
FORCEPROP 2 LAST BOM_COST PROC
J 0
(-4000 2950);
PAINT MONO (-4000 2950);
DISPLAY INVISIBLE (-4000 2950);
FORCEPROP 2 LAST CDS_SEC 1
J 0
(-3950 3175);
DISPLAY 1.021277 (-3950 3175);
PAINT ORANGE (-3950 3175);
DISPLAY INVISIBLE (-3950 3175);
FORCEPROP 2 LAST $SEC 1
J 0
(-3950 3175);
DISPLAY 0.680851 (-3950 3175);
PAINT MONO (-3950 3175);
DISPLAY INVISIBLE (-3950 3175);
FORCEPROP 2 LAST CDS_LOCATION R2T37
J 0
(-3955 3075);
DISPLAY 0.617021 (-3955 3075);
PAINT AQUA (-3955 3075);
DISPLAY INVISIBLE (-3955 3075);
FORCEPROP 1 LAST PATH I94
J 0
(-3950 3125);
DISPLAY 0.978723 (-3950 3125);
PAINT WHITE (-3950 3125);
DISPLAY INVISIBLE (-3950 3125);
FORCEPROP 2 LAST ROOM PROC_SIDEBAND
J 0
(-3975 2725);
PAINT ORANGE (-3975 2725);
DISPLAY INVISIBLE (-3975 2725);
FORCEPROP 1 LASTPIN (-4000 2850) $PN 2
J 0
(-3995 2860);
DISPLAY 0.787234 (-3995 2860);
PAINT ORANGE (-3995 2860);
DISPLAY INVISIBLE (-3995 2860);
FORCEPROP 1 LASTPIN (-4000 3050) $PN 1
J 0
(-3995 3012);
DISPLAY 0.787234 (-3995 3012);
PAINT ORANGE (-3995 3012);
DISPLAY INVISIBLE (-3995 3012);
FORCEADD PVCCIO_CPU0..1
(-4000 3175);
FORCEPROP 3 LASTPIN (-4000 3125) SIG_NAME PVCCIO_CPU0\g
J 0
(-3990 3135);
DISPLAY 0.659574 (-3990 3135);
PAINT MONO (-3990 3135);
DISPLAY INVISIBLE (-3990 3135);
FORCEPROP 1 LAST VOLTAGE 1.1V
J 0
(-4045 3132);
DISPLAY 0.340426 (-4045 3132);
PAINT SKYBLUE (-4045 3132);
DISPLAY INVISIBLE (-4045 3132);
FORCEPROP 2 LAST CDS_LIB mstr_symbols
J 0
(-4000 3175);
PAINT ORANGE (-4000 3175);
DISPLAY INVISIBLE (-4000 3175);
FORCEPROP 1 LAST PATH I95
J 0
(-3950 3200);
DISPLAY 0.872340 (-3950 3200);
PAINT AQUA (-3950 3200);
DISPLAY INVISIBLE (-3950 3200);
FORCEPROP 1 LAST BODY_TYPE PLUMBING
J 0
(-4045 3132);
DISPLAY 0.340426 (-4045 3132);
PAINT GREEN (-4045 3132);
DISPLAY INVISIBLE (-4045 3132);
FORCEPROP 1 LAST HDL_POWER PVCCIO_CPU0
J 1
(-4000 3225);
DISPLAY 0.872340 (-4000 3225);
PAINT GREEN (-4000 3225);
DISPLAY INVISIBLE (-4000 3225);
FORCEADD RES..1
(-3675 2675);
FORCEPROP 1 LAST VALUE 75
J 2
(-3700 2575);
DISPLAY 0.617021 (-3700 2575);
PAINT SKYBLUE (-3700 2575);
FORCEPROP 1 LAST TOLERANCE 1.0%
J 0
(-3675 2575);
DISPLAY 0.617021 (-3675 2575);
PAINT SKYBLUE (-3675 2575);
FORCEPROP 1 LAST MATERIAL CHIP
J 0
(-3675 2525);
DISPLAY 0.617021 (-3675 2525);
PAINT SKYBLUE (-3675 2525);
FORCEPROP 1 LAST WATTAGE 1/16W
J 2
(-3700 2525);
DISPLAY 0.617021 (-3700 2525);
PAINT SKYBLUE (-3700 2525);
FORCEPROP 1 LASTPIN (-3575 2675) $PN 2
J 0
(-3613 2687);
DISPLAY 0.617021 (-3613 2687);
PAINT ORANGE (-3613 2687);
FORCEPROP 1 LASTPIN (-3775 2675) $PN 1
J 0
(-3763 2687);
DISPLAY 0.617021 (-3763 2687);
PAINT ORANGE (-3763 2687);
FORCEPROP 1 LAST PACK_TYPE 0402
J 0
(-3750 2475);
DISPLAY 0.617021 (-3750 2475);
PAINT SKYBLUE (-3750 2475);
FORCEPROP 1 LAST PART_NUMBER G21796-267
J 0
(-3725 2775);
DISPLAY 0.617021 (-3725 2775);
PAINT BLUE (-3725 2775);
FORCEPROP 1 LAST LOCATION R2T43
J 0
(-3725 2725);
DISPLAY 0.617021 (-3725 2725);
PAINT AQUA (-3725 2725);
FORCEPROP 2 LAST BOM_COST PROC
J 2
(-3675 2675);
PAINT MONO (-3675 2675);
DISPLAY INVISIBLE (-3675 2675);
FORCEPROP 2 LAST CDS_LIB mstr_discrete
J 0
(-3675 2675);
PAINT ORANGE (-3675 2675);
DISPLAY INVISIBLE (-3675 2675);
FORCEPROP 2 LAST CDS_SEC 1
J 0
(-3725 2875);
DISPLAY 1.021277 (-3725 2875);
PAINT ORANGE (-3725 2875);
DISPLAY INVISIBLE (-3725 2875);
FORCEPROP 2 LAST $SEC 1
J 0
(-3725 2875);
DISPLAY 0.680851 (-3725 2875);
PAINT MONO (-3725 2875);
DISPLAY INVISIBLE (-3725 2875);
FORCEPROP 2 LAST CDS_LOCATION R2T43
J 0
(-3725 2725);
DISPLAY 0.617021 (-3725 2725);
PAINT AQUA (-3725 2725);
DISPLAY INVISIBLE (-3725 2725);
FORCEPROP 1 LAST PATH I96
J 0
(-3725 2825);
DISPLAY 0.978723 (-3725 2825);
PAINT WHITE (-3725 2825);
DISPLAY INVISIBLE (-3725 2825);
FORCEPROP 2 LAST ROOM PROC_SIDEBAND
J 0
(-3750 2600);
DISPLAY 0.617021 (-3750 2600);
PAINT ORANGE (-3750 2600);
DISPLAY INVISIBLE (-3750 2600);
FORCEADD RES..1
(-3775 4350);
FORCEPROP 1 LAST LOCATION R3P59
J 0
(-3850 4400);
DISPLAY 0.617021 (-3850 4400);
PAINT AQUA (-3850 4400);
FORCEPROP 1 LAST PART_NUMBER G21497-005
J 0
(-3975 4250);
DISPLAY 0.617021 (-3975 4250);
PAINT BLUE (-3975 4250);
FORCEPROP 1 LAST VALUE 0.0
J 2
(-3900 4350);
DISPLAY 0.617021 (-3900 4350);
PAINT SKYBLUE (-3900 4350);
FORCEPROP 1 LAST TOLERANCE 5%
J 0
(-3750 4250);
DISPLAY 0.617021 (-3750 4250);
PAINT SKYBLUE (-3750 4250);
FORCEPROP 1 LAST PACK_TYPE 0402
J 0
(-3825 4300);
DISPLAY 0.617021 (-3825 4300);
PAINT SKYBLUE (-3825 4300);
FORCEPROP 1 LAST MATERIAL CHIP
J 0
(-3950 4300);
DISPLAY 0.617021 (-3950 4300);
PAINT SKYBLUE (-3950 4300);
FORCEPROP 1 LAST WATTAGE 1/16W
J 2
(-3600 4300);
DISPLAY 0.617021 (-3600 4300);
PAINT SKYBLUE (-3600 4300);
FORCEPROP 1 LASTPIN (-3675 4350) $PN 2
J 0
(-3713 4362);
DISPLAY 0.617021 (-3713 4362);
PAINT MONO (-3713 4362);
FORCEPROP 1 LASTPIN (-3875 4350) $PN 1
J 0
(-3863 4362);
DISPLAY 0.617021 (-3863 4362);
PAINT MONO (-3863 4362);
FORCEPROP 2 LAST CDS_LIB mstr_discrete
J 0
(-3775 4350);
PAINT ORANGE (-3775 4350);
DISPLAY INVISIBLE (-3775 4350);
FORCEPROP 2 LAST SEC_TYPE 0402
J 0
(-3825 4550);
DISPLAY 1.021277 (-3825 4550);
PAINT ORANGE (-3825 4550);
DISPLAY INVISIBLE (-3825 4550);
FORCEPROP 2 LAST BOM_COST PROC
J 2
(-3775 4350);
PAINT MONO (-3775 4350);
DISPLAY INVISIBLE (-3775 4350);
FORCEPROP 2 LAST SEC 1
J 0
(-3825 4550);
DISPLAY 0.680851 (-3825 4550);
PAINT MONO (-3825 4550);
DISPLAY INVISIBLE (-3825 4550);
FORCEPROP 1 LAST PATH I97
J 0
(-3825 4500);
DISPLAY 0.978723 (-3825 4500);
PAINT WHITE (-3825 4500);
DISPLAY INVISIBLE (-3825 4500);
FORCEPROP 2 LAST ROOM PROC_SIDEBAND
J 0
(-3850 4275);
DISPLAY 0.617021 (-3850 4275);
PAINT ORANGE (-3850 4275);
DISPLAY INVISIBLE (-3850 4275);
FORCEADD RES..1
(-3750 4100);
FORCEPROP 1 LAST LOCATION R3P58
J 0
(-3825 4150);
DISPLAY 0.617021 (-3825 4150);
PAINT AQUA (-3825 4150);
FORCEPROP 1 LAST PART_NUMBER G21497-005
J 0
(-3950 4000);
DISPLAY 0.617021 (-3950 4000);
PAINT BLUE (-3950 4000);
FORCEPROP 1 LAST VALUE 0.0
J 2
(-3875 4100);
DISPLAY 0.617021 (-3875 4100);
PAINT SKYBLUE (-3875 4100);
FORCEPROP 1 LAST TOLERANCE 5%
J 0
(-3725 4000);
DISPLAY 0.617021 (-3725 4000);
PAINT SKYBLUE (-3725 4000);
FORCEPROP 1 LAST PACK_TYPE 0402
J 0
(-3825 4050);
DISPLAY 0.617021 (-3825 4050);
PAINT SKYBLUE (-3825 4050);
FORCEPROP 1 LAST MATERIAL CHIP
J 0
(-3950 4050);
DISPLAY 0.617021 (-3950 4050);
PAINT SKYBLUE (-3950 4050);
FORCEPROP 1 LAST WATTAGE 1/16W
J 2
(-3600 4050);
DISPLAY 0.617021 (-3600 4050);
PAINT SKYBLUE (-3600 4050);
FORCEPROP 1 LASTPIN (-3650 4100) $PN 2
J 0
(-3688 4112);
DISPLAY 0.617021 (-3688 4112);
PAINT MONO (-3688 4112);
FORCEPROP 1 LASTPIN (-3850 4100) $PN 1
J 0
(-3838 4112);
DISPLAY 0.617021 (-3838 4112);
PAINT MONO (-3838 4112);
FORCEPROP 2 LAST BOM_COST PROC
J 0
(-3750 4100);
PAINT MONO (-3750 4100);
DISPLAY INVISIBLE (-3750 4100);
FORCEPROP 2 LAST SEC_TYPE 0402
J 0
(-3800 4300);
DISPLAY 1.021277 (-3800 4300);
PAINT ORANGE (-3800 4300);
DISPLAY INVISIBLE (-3800 4300);
FORCEPROP 2 LAST CDS_LIB mstr_discrete
J 0
(-3750 4100);
PAINT ORANGE (-3750 4100);
DISPLAY INVISIBLE (-3750 4100);
FORCEPROP 2 LAST SEC 1
J 0
(-3800 4300);
DISPLAY 0.680851 (-3800 4300);
PAINT MONO (-3800 4300);
DISPLAY INVISIBLE (-3800 4300);
FORCEPROP 1 LAST PATH I98
J 0
(-3800 4250);
DISPLAY 0.978723 (-3800 4250);
PAINT WHITE (-3800 4250);
DISPLAY INVISIBLE (-3800 4250);
FORCEPROP 2 LAST ROOM PROC_SIDEBAND
J 0
(-3825 4025);
DISPLAY 0.617021 (-3825 4025);
PAINT ORANGE (-3825 4025);
DISPLAY INVISIBLE (-3825 4025);
FORCEADD PVCCIO_CPU0..1
(-4450 4850);
FORCEPROP 3 LASTPIN (-4450 4800) SIG_NAME PVCCIO_CPU0\g
J 0
(-4440 4810);
DISPLAY 0.659574 (-4440 4810);
PAINT MONO (-4440 4810);
DISPLAY INVISIBLE (-4440 4810);
FORCEPROP 1 LAST VOLTAGE 1.1V
J 0
(-4495 4807);
DISPLAY 0.340426 (-4495 4807);
PAINT SKYBLUE (-4495 4807);
DISPLAY INVISIBLE (-4495 4807);
FORCEPROP 2 LAST CDS_LIB mstr_symbols
J 0
(-4450 4850);
PAINT ORANGE (-4450 4850);
DISPLAY INVISIBLE (-4450 4850);
FORCEPROP 1 LAST PATH I99
J 0
(-4400 4875);
DISPLAY 0.872340 (-4400 4875);
PAINT AQUA (-4400 4875);
DISPLAY INVISIBLE (-4400 4875);
FORCEPROP 1 LAST BODY_TYPE PLUMBING
J 0
(-4495 4807);
DISPLAY 0.340426 (-4495 4807);
PAINT GREEN (-4495 4807);
DISPLAY INVISIBLE (-4495 4807);
FORCEPROP 1 LAST HDL_POWER PVCCIO_CPU0
J 1
(-4450 4900);
DISPLAY 0.872340 (-4450 4900);
PAINT GREEN (-4450 4900);
DISPLAY INVISIBLE (-4450 4900);
FORCEADD DNS..2
(-95 3045);
PAINT RED (-95 3045);
FORCEPROP 2 LAST CDS_LIB mstr_misc
J 0
(-95 3045);
PAINT ORANGE (-95 3045);
DISPLAY INVISIBLE (-95 3045);
FORCEPROP 1 LAST COMMENT_BODY TRUE
R 1
J 0
(-20 2820);
DISPLAY 0.872340 (-20 2820);
PAINT GREEN (-20 2820);
DISPLAY INVISIBLE (-20 2820);
FORCEADD INTEL_CORP_BPAGE..1
(2225 675);
FORCEPROP 1 LAST CDS_CON_LAST_MODIFIED Fri Jun 16 17:48:34 2017
J 0
(800 1000);
PAINT ORANGE (800 1000);
DISPLAY INVISIBLE (800 1000);
FORCEPROP 1 LAST CUSTOM_TXT_CDS <CURRENT_DESIGN_SHEET> OF <TOTAL_DESIGN_SHEETS>
J 0
(1725 700);
PAINT ORANGE (1725 700);
FORCEPROP 1 LAST CUSTOM_TXT_CDS <CON_LAST_MODIFIED>
J 0
(-1775 775);
PAINT ORANGE (-1775 775);
FORCEPROP 2 LAST CUSTOM_TXT_CDS <XR_PAGE_TITLE>
J 0
(-5665 5925);
DISPLAY 0.638298 (-5665 5925);
PAINT PINK (-5665 5925);
DISPLAY INVISIBLE (-5665 5925);
FORCEPROP 1 LAST SCH_TITLE CPU SIDE BAND: MISC
J 0
(-5725 725);
DISPLAY 1.212766 (-5725 725);
PAINT ORANGE (-5725 725);
FORCEPROP 2 LAST CDS_LIB mstr_symbols
J 0
(2225 675);
PAINT MONO (2225 675);
DISPLAY INVISIBLE (2225 675);
FORCEPROP 2 LAST PAGE_BORDER TRUE
J 0
(-5665 5925);
DISPLAY 0.638298 (-5665 5925);
PAINT PINK (-5665 5925);
DISPLAY INVISIBLE (-5665 5925);
FORCEPROP 2 LAST CDS_XR_PAGE_TITLE CR-92 : @BASEBOARD_FAB2_LIB.BASEBOARD_FAB2(SCH_1):PAGE92
J 0
(-5665 5925);
DISPLAY 0.638298 (-5665 5925);
PAINT PINK (-5665 5925);
DISPLAY INVISIBLE (-5665 5925);
FORCEPROP 1 LAST COMMENT_BODY TRUE
J 0
(2237 687);
DISPLAY 0.468085 (2237 687);
PAINT GREEN (2237 687);
DISPLAY INVISIBLE (2237 687);
FORCEADD CAD_NOTE..1
(-3775 1050);
FORCEPROP 0 LAST L1 * PLACE SERIES RESISTORS CLOSE TO  GTL2014
J 0
(-3925 950);
DISPLAY 0.808511 (-3925 950);
PAINT WHITE (-3925 950);
FORCEPROP 2 LAST CDS_LIB mstr_symbols
J 0
(-3775 1050);
PAINT MONO (-3775 1050);
DISPLAY INVISIBLE (-3775 1050);
FORCEPROP 2 LAST BOM_COST SM_CONTROLLER
J 0
(-3925 1000);
PAINT WHITE (-3925 1000);
DISPLAY INVISIBLE (-3925 1000);
FORCEPROP 2 LAST ROOM BMC
J 0
(-3925 1000);
PAINT WHITE (-3925 1000);
DISPLAY INVISIBLE (-3925 1000);
FORCEPROP 1 LAST COMMENT_BODY TRUE
J 0
(-3750 1150);
DISPLAY 1.319149 (-3750 1150);
PAINT WHITE (-3750 1150);
DISPLAY INVISIBLE (-3750 1150);
FORCEADD DESIGN_NOTE..1
(-2150 3675);
PAINT PURPLE (-2150 3675);
FORCEPROP 0 LAST L3 VREF IS SET AT 2/3 OF VCCIO
J 0
(-2350 3450);
DISPLAY 0.808511 (-2350 3450);
PAINT VIOLET (-2350 3450);
FORCEPROP 0 LAST L2 THE PINS 'BX' ARE INPUTS & 'AX' OUTPUTS ARE PUSH-PULL.
J 0
(-2350 3500);
DISPLAY 0.808511 (-2350 3500);
PAINT VIOLET (-2350 3500);
FORCEPROP 0 LAST L1 THE GTL2014 IS BEING USED AS GTL TO LVTTL CONVERTER, SO
J 0
(-2350 3550);
DISPLAY 0.808511 (-2350 3550);
PAINT VIOLET (-2350 3550);
FORCEPROP 2 LAST BOM_COST SM_CONTROLLER
J 0
(-2350 3625);
PAINT MONO (-2350 3625);
DISPLAY INVISIBLE (-2350 3625);
FORCEPROP 2 LAST CDS_LIB mstr_symbols
J 0
(-2150 3675);
PAINT ORANGE (-2150 3675);
DISPLAY INVISIBLE (-2150 3675);
FORCEPROP 2 LAST ROOM PVCCIN_CPU1_DECAP_VR
J 0
(-2350 3625);
PAINT MONO (-2350 3625);
DISPLAY INVISIBLE (-2350 3625);
FORCEPROP 1 LAST COMMENT_BODY TRUE
J 0
(-2125 3775);
DISPLAY 1.319149 (-2125 3775);
PAINT GREEN (-2125 3775);
DISPLAY INVISIBLE (-2125 3775);
FORCEADD DESIGN_NOTE..1
(-1950 1500);
PAINT PURPLE (-1950 1500);
FORCEPROP 0 LAST L3 VREF IS SET AT 2/3 OF VCCIO
J 0
(-2150 1275);
DISPLAY 0.808511 (-2150 1275);
PAINT VIOLET (-2150 1275);
FORCEPROP 0 LAST L2 THE PINS 'BX' ARE INPUTS & 'AX' OUTPUTS ARE PUSH-PULL.
J 0
(-2150 1325);
DISPLAY 0.808511 (-2150 1325);
PAINT VIOLET (-2150 1325);
FORCEPROP 0 LAST L1 THE GTL2014 IS BEING USED AS GTL TO LVTTL CONVERTER, SO
J 0
(-2150 1375);
DISPLAY 0.808511 (-2150 1375);
PAINT VIOLET (-2150 1375);
FORCEPROP 2 LAST CDS_LIB mstr_symbols
J 0
(-1950 1500);
PAINT ORANGE (-1950 1500);
DISPLAY INVISIBLE (-1950 1500);
FORCEPROP 2 LAST BOM_COST SM_CONTROLLER
J 0
(-2150 1450);
PAINT MONO (-2150 1450);
DISPLAY INVISIBLE (-2150 1450);
FORCEPROP 2 LAST ROOM PVCCIN_CPU1_DECAP_VR
J 0
(-2150 1450);
PAINT MONO (-2150 1450);
DISPLAY INVISIBLE (-2150 1450);
FORCEPROP 1 LAST COMMENT_BODY TRUE
J 0
(-1925 1600);
DISPLAY 1.319149 (-1925 1600);
PAINT GREEN (-1925 1600);
DISPLAY INVISIBLE (-1925 1600);
FORCEADD CAD_NOTE..1
(-4750 2275);
FORCEPROP 0 LAST L1 PLACE PULLUP RESISTOR WITHIN 2.5 INCH OF CPU0
J 0
(-4900 2175);
DISPLAY 0.638298 (-4900 2175);
PAINT ORANGE (-4900 2175);
FORCEPROP 2 LAST CDS_LIB mstr_symbols
J 0
(-4750 2275);
PAINT ORANGE (-4750 2275);
DISPLAY INVISIBLE (-4750 2275);
FORCEPROP 2 LAST BOM_COST SM_CONTROLLER
J 0
(-4900 2225);
PAINT WHITE (-4900 2225);
DISPLAY INVISIBLE (-4900 2225);
FORCEPROP 2 LAST ROOM PROC_SIDEBAND
J 0
(-4900 2225);
PAINT WHITE (-4900 2225);
DISPLAY INVISIBLE (-4900 2225);
FORCEPROP 1 LAST COMMENT_BODY TRUE
J 0
(-4725 2375);
DISPLAY 1.319149 (-4725 2375);
PAINT WHITE (-4725 2375);
DISPLAY INVISIBLE (-4725 2375);
FORCEADD CAD_NOTE..1
(-2875 4975);
FORCEPROP 0 LAST L1 * PLACE PULL-UP RESISTORS CLOSE TO GTL2014
J 0
(-3025 4875);
DISPLAY 0.638298 (-3025 4875);
PAINT WHITE (-3025 4875);
FORCEPROP 2 LAST CDS_LIB mstr_symbols
J 0
(-2875 4975);
PAINT ORANGE (-2875 4975);
DISPLAY INVISIBLE (-2875 4975);
FORCEPROP 2 LAST BOM_COST SM_CONTROLLER
J 0
(-3025 4925);
PAINT WHITE (-3025 4925);
DISPLAY INVISIBLE (-3025 4925);
FORCEPROP 2 LAST ROOM BMC
J 0
(-3025 4925);
PAINT WHITE (-3025 4925);
DISPLAY INVISIBLE (-3025 4925);
FORCEPROP 1 LAST COMMENT_BODY TRUE
J 0
(-2850 5075);
DISPLAY 1.319149 (-2850 5075);
PAINT WHITE (-2850 5075);
DISPLAY INVISIBLE (-2850 5075);
FORCEADD CAD_NOTE..1
(-3950 3875);
FORCEPROP 0 LAST L1 PLACE SERIES RESISTORS NEAR GTL CONVERTER
J 0
(-4100 3775);
DISPLAY 0.638298 (-4100 3775);
PAINT ORANGE (-4100 3775);
FORCEPROP 2 LAST CDS_LIB mstr_symbols
J 0
(-3950 3875);
PAINT WHITE (-3950 3875);
DISPLAY INVISIBLE (-3950 3875);
FORCEPROP 1 LAST COMMENT_BODY TRUE
J 0
(-3925 3975);
DISPLAY 1.319149 (-3925 3975);
PAINT WHITE (-3925 3975);
DISPLAY INVISIBLE (-3925 3975);
FORCEADD CAD_NOTE..1
(-2875 3525);
FORCEPROP 0 LAST L1 * PLACE  RESISTORS CLOSE TO  GTL2014
J 0
(-3350 3425);
DISPLAY 0.638298 (-3350 3425);
PAINT WHITE (-3350 3425);
FORCEPROP 2 LAST CDS_LIB mstr_symbols
J 0
(-2875 3525);
PAINT MONO (-2875 3525);
DISPLAY INVISIBLE (-2875 3525);
FORCEPROP 2 LAST BOM_COST SM_CONTROLLER
J 0
(-3025 3475);
PAINT WHITE (-3025 3475);
DISPLAY INVISIBLE (-3025 3475);
FORCEPROP 2 LAST ROOM BMC
J 0
(-3025 3475);
PAINT WHITE (-3025 3475);
DISPLAY INVISIBLE (-3025 3475);
FORCEPROP 1 LAST COMMENT_BODY TRUE
J 0
(-2850 3625);
DISPLAY 1.319149 (-2850 3625);
PAINT WHITE (-2850 3625);
DISPLAY INVISIBLE (-2850 3625);
FORCEADD CAD_NOTE..1
(-4425 3425);
FORCEPROP 0 LAST L1 PLACE ALL COMPONENTS NEAR GTL CONVERTER
J 0
(-4575 3325);
DISPLAY 0.638298 (-4575 3325);
PAINT ORANGE (-4575 3325);
FORCEPROP 2 LAST CDS_LIB mstr_symbols
J 0
(-4425 3425);
PAINT ORANGE (-4425 3425);
DISPLAY INVISIBLE (-4425 3425);
FORCEPROP 2 LAST BOM_COST SM_CONTROLLER
J 0
(-4575 3375);
PAINT WHITE (-4575 3375);
DISPLAY INVISIBLE (-4575 3375);
FORCEPROP 2 LAST ROOM PROC_SIDEBAND
J 0
(-4575 3375);
PAINT WHITE (-4575 3375);
DISPLAY INVISIBLE (-4575 3375);
FORCEPROP 1 LAST COMMENT_BODY TRUE
J 0
(-4400 3525);
DISPLAY 1.319149 (-4400 3525);
PAINT WHITE (-4400 3525);
DISPLAY INVISIBLE (-4400 3525);
FORCEADD CAD_NOTE..1
(-2875 2975);
FORCEPROP 0 LAST L1 * PLACE PULL-UP RESISTORS CLOSE TO GTL2014
J 0
(-3025 2850);
DISPLAY 0.638298 (-3025 2850);
PAINT WHITE (-3025 2850);
FORCEPROP 2 LAST BOM_COST SM_CONTROLLER
J 0
(-3025 2925);
PAINT WHITE (-3025 2925);
DISPLAY INVISIBLE (-3025 2925);
FORCEPROP 2 LAST CDS_LIB mstr_symbols
J 0
(-2875 2975);
PAINT ORANGE (-2875 2975);
DISPLAY INVISIBLE (-2875 2975);
FORCEPROP 2 LAST ROOM BMC
J 0
(-3025 2925);
PAINT WHITE (-3025 2925);
DISPLAY INVISIBLE (-3025 2925);
FORCEPROP 1 LAST COMMENT_BODY TRUE
J 0
(-2850 3075);
DISPLAY 1.319149 (-2850 3075);
PAINT WHITE (-2850 3075);
DISPLAY INVISIBLE (-2850 3075);
FORCEADD CAD_NOTE..1
(-4700 5125);
FORCEPROP 0 LAST L2 2.5 INCH OF CPU0
J 0
(-4850 4975);
DISPLAY 0.638298 (-4850 4975);
PAINT ORANGE (-4850 4975);
FORCEPROP 0 LAST L1 PLACE PULLUP RESISTOR WITHIN
J 0
(-4850 5025);
DISPLAY 0.638298 (-4850 5025);
PAINT ORANGE (-4850 5025);
FORCEPROP 2 LAST BOM_COST SM_CONTROLLER
J 0
(-4850 5075);
PAINT WHITE (-4850 5075);
DISPLAY INVISIBLE (-4850 5075);
FORCEPROP 2 LAST CDS_LIB mstr_symbols
J 0
(-4700 5125);
PAINT ORANGE (-4700 5125);
DISPLAY INVISIBLE (-4700 5125);
FORCEPROP 2 LAST ROOM PROC_SIDEBAND
J 0
(-4850 5075);
PAINT WHITE (-4850 5075);
DISPLAY INVISIBLE (-4850 5075);
FORCEPROP 1 LAST COMMENT_BODY TRUE
J 0
(-4675 5225);
DISPLAY 1.319149 (-4675 5225);
PAINT WHITE (-4675 5225);
DISPLAY INVISIBLE (-4675 5225);
FORCEADD DNS..2
(-395 5345);
PAINT RED (-395 5345);
FORCEPROP 2 LAST CDS_LIB mstr_misc
J 0
(-395 5345);
PAINT ORANGE (-395 5345);
DISPLAY INVISIBLE (-395 5345);
FORCEPROP 1 LAST COMMENT_BODY TRUE
R 1
J 0
(-320 5120);
DISPLAY 0.872340 (-320 5120);
PAINT GREEN (-320 5120);
DISPLAY INVISIBLE (-320 5120);
WIRE 16 -1 (-2900 4700)(-2900 4625);
WIRE 16 -1 (100 5500)(100 5450);
WIRE 16 -1 (350 3150)(350 3200);
WIRE 16 -1 (-100 3200)(-100 3150);
WIRE 16 -1 (-400 5500)(-400 5450);
WIRE 16 -1 (-2550 3850)(-2550 3775);
WIRE 16 -1 (-2550 3900)(-2550 3850);
WIRE 16 -1 (-2550 3850)(-2275 3850);
WIRE 16 -1 (-2550 3950)(-2550 3900);
WIRE 16 -1 (-2275 3900)(-2550 3900);
WIRE 16 -1 (-2275 3950)(-2550 3950);
WIRE 16 -1 (-2475 1650)(-2475 1575);
WIRE 16 -1 (-2475 1700)(-2475 1650);
WIRE 16 -1 (-2475 1650)(-2200 1650);
WIRE 16 -1 (-2475 1750)(-2475 1700);
WIRE 16 -1 (-2200 1700)(-2475 1700);
WIRE 16 -1 (-2200 1750)(-2475 1750);
WIRE 16 -1 (100 4550)(100 4500);
WIRE 16 -1 (-400 4550)(100 4550);
WIRE 16 -1 (100 4700)(100 4550);
WIRE 16 -1 (-400 4700)(-400 4550);
WIRE 16 -1 (-1175 4900)(-1175 4875);
WIRE 16 -1 (-1025 4875)(-1175 4875);
WIRE 16 -1 (-1175 4875)(-1175 4550);
WIRE 16 -1 (-1175 4550)(-1375 4550);
WIRE 16 -1 (-1025 4825)(-1025 4875);
WIRE 16 -1 (-300 4375)(-300 4400);
WIRE 16 -1 (-575 4400)(-300 4400);
WIRE 16 -1 (350 2300)(350 2250);
WIRE 16 -1 (-100 2300)(350 2300);
WIRE 16 -1 (350 2450)(350 2300);
WIRE 16 -1 (-100 2450)(-100 2300);
WIRE 16 -1 (-225 2175)(-225 2200);
WIRE 16 -1 (-500 2200)(-225 2200);
WIRE 16 -1 (-1050 2700)(-1050 2675);
WIRE 16 -1 (-900 2675)(-1050 2675);
WIRE 16 -1 (-1050 2675)(-1050 2350);
WIRE 16 -1 (-1050 2350)(-1300 2350);
WIRE 16 -1 (-900 2625)(-900 2675);
WIRE 16 -1 (-4600 1950)(-4600 2000);
WIRE 16 -1 (-4600 1950)(-4275 1950);
WIRE 16 -1 (-4600 1925)(-4600 1950);
WIRE 16 -1 (-4275 1900)(-4275 1950);
WIRE 16 -1 (-2925 3800)(-2925 3700);
WIRE 16 -1 (-900 2400)(-900 2425);
WIRE 16 -1 (-2850 2425)(-2850 2650);
WIRE 16 -1 (-1025 4600)(-1025 4625);
WIRE 16 -1 (-4000 3050)(-4000 3125);
WIRE 16 -1 (-4450 4800)(-4450 4750);
WIRE 16 -1 (-4350 4750)(-4450 4750);
WIRE 16 -1 (-4450 4750)(-4450 4700);
WIRE 16 -1 (-4350 4700)(-4350 4750);
WIRE 16 -1 (-675 3550)(-225 3550);
WIRE 16 -1 (-675 4100)(-675 3550);
WIRE 16 -1 (-1375 4100)(-675 4100);
FORCEPROP 2 LAST SIG_NAME PWRGD_CPUPWRGD_R1
J 0
(-1250 4110);
DISPLAY 0.617021 (-1250 4110);
PAINT ORANGE (-1250 4110);
FORCEPROP 2 LASTPROP $XRERR UNIQUE?
J 0
(-1490 4110);
DISPLAY 0.638298 (-1490 4110);
PAINT MONO (-1490 4110);
DISPLAY INVISIBLE (-1490 4110);
WIRE 16 2175 (-2975 3600)(-2975 4075);
WIRE 16 2175 (-2700 3600)(-2975 3600);
WIRE 16 2175 (-2975 4075)(-2700 4075);
WIRE 16 2175 (-2700 4075)(-2700 3600);
WIRE 16 -1 (-3000 4250)(-2900 4250);
WIRE 16 -1 (-2900 4425)(-2900 4250);
WIRE 16 -1 (-2275 4250)(-2900 4250);
FORCEPROP 2 LAST SIG_NAME H_CPU1_THERMTRIP_G_N
J 0
(-2850 4265);
DISPLAY 0.617021 (-2850 4265);
PAINT ORANGE (-2850 4265);
WIRE 16 -1 (-3450 4100)(-3650 4100);
WIRE 16 -1 (-3675 4350)(-3450 4350);
WIRE 16 -1 (-3450 4350)(-3450 4200);
WIRE 16 -1 (-3450 4100)(-3450 4200);
WIRE 16 -1 (-3450 4200)(-2275 4200);
FORCEPROP 2 LAST SIG_NAME H_CPU_CATERR_G_N
J 0
(-2800 4210);
DISPLAY 0.617021 (-2800 4210);
PAINT ORANGE (-2800 4210);
FORCEPROP 2 LASTPROP $XRERR UNIQUE?
J 0
(-3040 4210);
DISPLAY 0.638298 (-3040 4210);
PAINT MONO (-3040 4210);
DISPLAY INVISIBLE (-3040 4210);
WIRE 16 2175 (-4800 2375)(-4800 3300);
WIRE 16 2175 (-3400 2375)(-4800 2375);
WIRE 16 2175 (-4800 3300)(-3400 3300);
WIRE 16 2175 (-3400 3300)(-3400 2375);
WIRE 16 -1 (-3500 2675)(-3575 2675);
WIRE 16 -1 (-3500 2000)(-2200 2000);
FORCEPROP 2 LAST SIG_NAME H_CPU_ERR2_GTL_N
J 0
(-2810 2010);
DISPLAY 0.617021 (-2810 2010);
PAINT ORANGE (-2810 2010);
FORCEPROP 2 LASTPROP $XRERR UNIQUE?
J 0
(-3050 2010);
DISPLAY 0.638298 (-3050 2010);
PAINT MONO (-3050 2010);
DISPLAY INVISIBLE (-3050 2010);
WIRE 16 -1 (-3500 2000)(-3500 2675);
WIRE 16 -1 (-500 2300)(-1300 2300);
WIRE 16 -1 (-500 2750)(-500 2300);
WIRE 16 -1 (-100 2750)(-500 2750);
FORCEPROP 0 LAST VOLTAGE +0.7 V
J 0
(-300 2825);
DISPLAY 1.404255 (-300 2825);
PAINT SKYBLUE (-300 2825);
DISPLAY INVISIBLE (-300 2825);
FORCEPROP 2 LAST SIG_NAME P0V7_GTL2104_VREF_0
J 0
(-335 2760);
DISPLAY 0.617021 (-335 2760);
PAINT ORANGE (-335 2760);
FORCEPROP 2 LASTPROP $XRERR UNIQUE?
J 0
(-575 2760);
DISPLAY 0.638298 (-575 2760);
PAINT MONO (-575 2760);
DISPLAY INVISIBLE (-575 2760);
WIRE 16 -1 (-100 2650)(-100 2750);
WIRE 16 -1 (350 2750)(-100 2750);
WIRE 16 -1 (350 2750)(350 2650);
WIRE 16 -1 (350 2800)(350 2750);
WIRE 16 -1 (350 2900)(350 2800);
WIRE 16 -1 (-100 2800)(350 2800);
WIRE 16 -1 (-100 2950)(-100 2800);
WIRE 3 682 (650 2850)(250 2850);
WIRE 3 682 (250 3425)(250 2850);
WIRE 3 682 (650 2850)(650 3425);
WIRE 3 682 (650 3425)(250 3425);
WIRE 16 2175 (-4100 4050)(-4700 4050);
WIRE 16 2175 (-4100 4950)(-4100 4050);
WIRE 16 2175 (-4700 4050)(-4700 4950);
WIRE 16 2175 (-4700 4950)(-4100 4950);
WIRE 16 -1 (-525 4000)(-225 4000);
WIRE 16 -1 (-525 4200)(-525 4000);
WIRE 16 -1 (-1375 4200)(-525 4200);
FORCEPROP 2 LAST SIG_NAME FM_CPU_CATERR_LVT3_R2_N
J 0
(-1250 4210);
DISPLAY 0.617021 (-1250 4210);
PAINT ORANGE (-1250 4210);
FORCEPROP 2 LASTPROP $XRERR UNIQUE?
J 0
(-1490 4210);
DISPLAY 0.638298 (-1490 4210);
PAINT MONO (-1490 4210);
DISPLAY INVISIBLE (-1490 4210);
WIRE 16 -1 (-4450 4350)(-5100 4350);
FORCEPROP 2 LAST SIG_NAME H_CPU0_CATERR_G_N
J 0
(-5100 4360);
DISPLAY 0.617021 (-5100 4360);
PAINT ORANGE (-5100 4360);
WIRE 16 -1 (-4450 4500)(-4450 4350);
WIRE 16 -1 (-3875 4350)(-4450 4350);
WIRE 16 -1 (-4000 2850)(-4000 2675);
WIRE 16 -1 (-3775 2675)(-4000 2675);
WIRE 16 -1 (-4575 2550)(-4625 2550);
WIRE 16 -1 (-4575 2550)(-4575 2675);
WIRE 16 -1 (-4575 2675)(-4000 2675);
WIRE 16 -1 (-4575 2675)(-4575 2800);
WIRE 16 -1 (-4650 2800)(-4575 2800);
FORCEPROP 2 LAST SIG_NAME H_CPU_ERR2_G_R_N
J 0
(-4525 2685);
DISPLAY 0.617021 (-4525 2685);
PAINT ORANGE (-4525 2685);
FORCEPROP 2 LASTPROP $XRERR UNIQUE?
J 0
(-4765 2685);
DISPLAY 0.638298 (-4765 2685);
PAINT MONO (-4765 2685);
DISPLAY INVISIBLE (-4765 2685);
WIRE 16 -1 (-4825 2550)(-5300 2550);
FORCEPROP 2 LAST SIG_NAME H_CPU1_ERR2_G_N
J 0
(-5300 2560);
DISPLAY 0.617021 (-5300 2560);
PAINT ORANGE (-5300 2560);
WIRE 16 -1 (-5300 2800)(-4850 2800);
FORCEPROP 2 LAST SIG_NAME H_CPU0_ERR2_G_N
J 0
(-5300 2810);
DISPLAY 0.617021 (-5300 2810);
PAINT ORANGE (-5300 2810);
WIRE 16 -1 (-2925 4000)(-2925 4150);
WIRE 16 -1 (-2925 4150)(-2275 4150);
FORCEPROP 2 LAST SIG_NAME H_CPU1_FIVR_FAULT_G
J 0
(-2800 4157);
DISPLAY 0.617021 (-2800 4157);
PAINT ORANGE (-2800 4157);
WIRE 16 -1 (-3000 4150)(-2925 4150);
WIRE 16 -1 (-4600 1725)(-4600 1550);
WIRE 16 -1 (-3875 1550)(-4600 1550);
WIRE 16 -1 (-5075 1550)(-4600 1550);
FORCEPROP 2 LAST SIG_NAME H_CPU0_MSMI_G_N
J 0
(-4900 1560);
DISPLAY 0.617021 (-4900 1560);
PAINT ORANGE (-4900 1560);
WIRE 16 -1 (-4275 1275)(-5075 1275);
FORCEPROP 2 LAST SIG_NAME H_CPU1_MSMI_G_N
J 0
(-4900 1285);
DISPLAY 0.617021 (-4900 1285);
PAINT ORANGE (-4900 1285);
WIRE 16 -1 (-4275 1700)(-4275 1275);
WIRE 16 -1 (-3825 1275)(-4275 1275);
WIRE 16 2175 (-4925 1175)(-4925 2150);
WIRE 16 2175 (-4075 1175)(-4925 1175);
WIRE 16 2175 (-4925 2150)(-4075 2150);
WIRE 16 2175 (-4075 2150)(-4075 1175);
WIRE 16 -1 (-4350 4500)(-4350 4100);
WIRE 16 -1 (-3850 4100)(-4350 4100);
WIRE 16 -1 (-5100 4100)(-4350 4100);
FORCEPROP 2 LAST SIG_NAME H_CPU1_CATERR_G_N
J 0
(-5100 4110);
DISPLAY 0.617021 (-5100 4110);
PAINT ORANGE (-5100 4110);
WIRE 16 2175 (-3950 1800)(-3950 1150);
WIRE 16 2175 (-3475 1800)(-3950 1800);
WIRE 16 2175 (-3950 1150)(-3475 1150);
WIRE 16 2175 (-3475 1150)(-3475 1800);
WIRE 16 -1 (-3550 1550)(-3675 1550);
WIRE 16 -1 (-3550 1275)(-3625 1275);
WIRE 16 -1 (-3550 1425)(-3550 1275);
WIRE 16 -1 (-3550 1425)(-3550 1550);
WIRE 16 -1 (-2950 1900)(-2200 1900);
WIRE 16 -1 (-2950 1425)(-3550 1425);
WIRE 16 -1 (-2950 1425)(-2950 1900);
FORCEPROP 2 LAST SIG_NAME H_CPU_MSMI_G_N
J 0
(-2810 1910);
DISPLAY 0.617021 (-2810 1910);
PAINT ORANGE (-2810 1910);
FORCEPROP 2 LASTPROP $XRERR UNIQUE?
J 0
(-3050 1910);
DISPLAY 0.638298 (-3050 1910);
PAINT MONO (-3050 1910);
DISPLAY INVISIBLE (-3050 1910);
WIRE 16 -1 (-3175 1950)(-2200 1950);
FORCEPROP 2 LAST SIG_NAME H_CPU0_FIVR_FAULT_G
J 0
(-2808 1957);
DISPLAY 0.617021 (-2808 1957);
PAINT ORANGE (-2808 1957);
WIRE 16 -1 (-1300 2200)(-700 2200);
FORCEPROP 2 LAST SIG_NAME PD_GTL2104_DIR_0
J 0
(-1187 2223);
DISPLAY 0.617021 (-1187 2223);
PAINT ORANGE (-1187 2223);
FORCEPROP 2 LASTPROP $XRERR UNIQUE?
J 0
(-1427 2223);
DISPLAY 0.638298 (-1427 2223);
PAINT MONO (-1427 2223);
DISPLAY INVISIBLE (-1427 2223);
WIRE 16 -1 (-1300 2050)(-225 2050);
FORCEPROP 2 LAST SIG_NAME FM_CPU0_THERMTRIP_LVT3_R_N
J 0
(-1175 2060);
DISPLAY 0.617021 (-1175 2060);
PAINT ORANGE (-1175 2060);
FORCEPROP 2 LASTPROP $XRERR UNIQUE?
J 0
(-1415 2060);
DISPLAY 0.638298 (-1415 2060);
PAINT MONO (-1415 2060);
DISPLAY INVISIBLE (-1415 2060);
WIRE 16 2175 (-4025 3950)(-3525 3950);
WIRE 16 2175 (-4025 4525)(-4025 3950);
WIRE 16 2175 (-3525 3950)(-3525 4525);
WIRE 16 2175 (-3525 4525)(-4025 4525);
WIRE 16 -1 (-1375 4250)(-225 4250);
FORCEPROP 2 LAST SIG_NAME FM_CPU1_THERMTRIP_LVT3_R_N
J 0
(-1250 4260);
DISPLAY 0.617021 (-1250 4260);
PAINT ORANGE (-1250 4260);
FORCEPROP 2 LASTPROP $XRERR UNIQUE?
J 0
(-1490 4260);
DISPLAY 0.638298 (-1490 4260);
PAINT MONO (-1490 4260);
DISPLAY INVISIBLE (-1490 4260);
WIRE 16 -1 (-450 1800)(-200 1800);
WIRE 16 -1 (-450 2000)(-450 1800);
WIRE 16 -1 (-1300 2000)(-450 2000);
FORCEPROP 2 LAST SIG_NAME FM_CPU_ERR2_LVT3_R_N
J 0
(-1175 2010);
DISPLAY 0.617021 (-1175 2010);
PAINT ORANGE (-1175 2010);
FORCEPROP 2 LASTPROP $XRERR UNIQUE?
J 0
(-1415 2010);
DISPLAY 0.638298 (-1415 2010);
PAINT MONO (-1415 2010);
DISPLAY INVISIBLE (-1415 2010);
WIRE 16 -1 (-550 1250)(-200 1250);
WIRE 16 -1 (-550 1900)(-550 1250);
WIRE 16 -1 (-1300 1900)(-550 1900);
FORCEPROP 2 LAST SIG_NAME FM_CPU_MSMI_LVT3_R_N
J 0
(-1175 1910);
DISPLAY 0.617021 (-1175 1910);
PAINT ORANGE (-1175 1910);
FORCEPROP 2 LASTPROP $XRERR UNIQUE?
J 0
(-1415 1910);
DISPLAY 0.638298 (-1415 1910);
PAINT MONO (-1415 1910);
DISPLAY INVISIBLE (-1415 1910);
WIRE 16 -1 (-500 1550)(-200 1550);
WIRE 16 -1 (-500 1950)(-500 1550);
WIRE 16 -1 (-1300 1950)(-500 1950);
FORCEPROP 2 LAST SIG_NAME FM_CPU0_FIVR_FAULT_R_LVT3
J 0
(-1175 1960);
DISPLAY 0.617021 (-1175 1960);
PAINT ORANGE (-1175 1960);
FORCEPROP 2 LASTPROP $XRERR UNIQUE?
J 0
(-1415 1960);
DISPLAY 0.638298 (-1415 1960);
PAINT MONO (-1415 1960);
DISPLAY INVISIBLE (-1415 1960);
WIRE 16 -1 (-25 2050)(1025 2050);
FORCEPROP 2 LAST SIG_NAME FM_CPU0_THERMTRIP_LVT3_N
J 0
(200 2060);
DISPLAY 0.617021 (200 2060);
PAINT ORANGE (200 2060);
WIRE 16 2175 (-3025 2125)(-3025 2800);
WIRE 16 2175 (-2600 2800)(-3025 2800);
WIRE 16 2175 (-3025 2125)(-2600 2125);
WIRE 16 2175 (-2600 2125)(-2600 2800);
WIRE 16 -1 (0 1800)(1025 1800);
FORCEPROP 2 LAST SIG_NAME FM_CPU_ERR2_LVT3_N
J 0
(200 1810);
DISPLAY 0.617021 (200 1810);
PAINT ORANGE (200 1810);
WIRE 16 -1 (0 1250)(1025 1250);
FORCEPROP 2 LAST SIG_NAME FM_CPU_MSMI_LVT3_N
J 0
(200 1260);
DISPLAY 0.617021 (200 1260);
PAINT ORANGE (200 1260);
WIRE 16 -1 (0 1550)(1025 1550);
FORCEPROP 2 LAST SIG_NAME FM_CPU0_FIVR_FAULT_LVT3
J 0
(200 1560);
DISPLAY 0.617021 (200 1560);
PAINT ORANGE (200 1560);
WIRE 16 -1 (-25 4000)(1000 4000);
FORCEPROP 2 LAST SIG_NAME FM_CPU_CATERR_LVT3_N
J 0
(150 4010);
DISPLAY 0.617021 (150 4010);
PAINT ORANGE (150 4010);
WIRE 16 -1 (-25 3750)(1000 3750);
FORCEPROP 2 LAST SIG_NAME FM_CPU1_FIVR_FAULT_LVT3
J 0
(150 3760);
DISPLAY 0.617021 (150 3760);
PAINT ORANGE (150 3760);
WIRE 16 -1 (-25 4250)(1000 4250);
FORCEPROP 2 LAST SIG_NAME FM_CPU1_THERMTRIP_LVT3_N
J 0
(150 4260);
DISPLAY 0.617021 (150 4260);
PAINT ORANGE (150 4260);
WIRE 16 -1 (-3000 4100)(-2275 4100);
FORCEPROP 2 LAST SIG_NAME PWRGD_CPUPWRGD_GTL
J 0
(-2800 4110);
DISPLAY 0.617021 (-2800 4110);
PAINT ORANGE (-2800 4110);
WIRE 16 -1 (-3175 2050)(-2850 2050);
WIRE 16 -1 (-2850 2225)(-2850 2050);
WIRE 16 -1 (-2200 2050)(-2850 2050);
FORCEPROP 2 LAST SIG_NAME H_CPU0_THERMTRIP_G_N
J 0
(-2812 2065);
DISPLAY 0.617021 (-2812 2065);
PAINT ORANGE (-2812 2065);
WIRE 16 -1 (-1375 4400)(-775 4400);
FORCEPROP 2 LAST SIG_NAME PD_GTL2104_DIR_1
J 0
(-1237 4423);
DISPLAY 0.617021 (-1237 4423);
PAINT ORANGE (-1237 4423);
FORCEPROP 2 LASTPROP $XRERR UNIQUE?
J 0
(-1477 4423);
DISPLAY 0.638298 (-1477 4423);
PAINT MONO (-1477 4423);
DISPLAY INVISIBLE (-1477 4423);
WIRE 16 -1 (-575 3750)(-225 3750);
WIRE 16 -1 (-575 4150)(-575 3750);
WIRE 16 -1 (-1375 4150)(-575 4150);
FORCEPROP 2 LAST SIG_NAME FM_CPU1_FIVR_FAULT_R_LVT3
J 0
(-1250 4160);
DISPLAY 0.617021 (-1250 4160);
PAINT ORANGE (-1250 4160);
FORCEPROP 2 LASTPROP $XRERR UNIQUE?
J 0
(-1490 4160);
DISPLAY 0.638298 (-1490 4160);
PAINT MONO (-1490 4160);
DISPLAY INVISIBLE (-1490 4160);
WIRE 16 -1 (-25 3550)(1000 3550);
FORCEPROP 2 LAST SIG_NAME PWRGD_CPUPWRGD
J 0
(150 3560);
DISPLAY 0.617021 (150 3560);
PAINT ORANGE (150 3560);
WIRE 3 682 (450 5100)(450 5650);
WIRE 3 682 (450 5100)(0 5100);
WIRE 3 682 (450 5650)(0 5650);
WIRE 3 682 (0 5650)(0 5100);
WIRE 16 -1 (-750 4500)(-1375 4500);
WIRE 16 -1 (-750 5000)(-750 4500);
WIRE 16 -1 (-400 5000)(-750 5000);
FORCEPROP 0 LAST VOLTAGE +0.7 V
J 0
(-550 5075);
DISPLAY 1.404255 (-550 5075);
PAINT SKYBLUE (-550 5075);
DISPLAY INVISIBLE (-550 5075);
FORCEPROP 2 LAST SIG_NAME P0V7_GTL2104_VREF_1
J 0
(-560 5010);
DISPLAY 0.617021 (-560 5010);
PAINT ORANGE (-560 5010);
FORCEPROP 2 LASTPROP $XRERR UNIQUE?
J 0
(-800 5010);
DISPLAY 0.638298 (-800 5010);
PAINT MONO (-800 5010);
DISPLAY INVISIBLE (-800 5010);
WIRE 16 -1 (-400 4900)(-400 5000);
WIRE 16 -1 (100 5000)(-400 5000);
WIRE 16 -1 (100 5000)(100 4900);
WIRE 16 -1 (-400 5250)(-400 5050);
WIRE 16 -1 (-400 5050)(100 5050);
WIRE 16 -1 (100 5050)(100 5000);
WIRE 16 -1 (100 5200)(100 5050);
WIRE 16 2175 (-3075 4325)(-3075 4850);
WIRE 16 2175 (-3075 4850)(-2625 4850);
WIRE 16 2175 (-2625 4325)(-3075 4325);
WIRE 16 2175 (-2625 4325)(-2625 4850);
DOT 1 (100 5050);
DOT 1 (-400 5000);
DOT 1 (100 5000);
DOT 1 (100 4550);
DOT 1 (-1050 2675);
DOT 1 (-3550 1425);
DOT 1 (-2475 1700);
DOT 1 (-4600 1550);
DOT 1 (-4275 1275);
DOT 1 (-4600 1950);
DOT 1 (-2550 3900);
DOT 1 (-1175 4875);
DOT 1 (-2900 4250);
DOT 1 (-3450 4200);
DOT 1 (-2550 3850);
DOT 1 (-4450 4750);
DOT 1 (-4450 4350);
DOT 1 (-4350 4100);
DOT 1 (-2850 2050);
DOT 1 (-2925 4150);
DOT 1 (-2475 1650);
DOT 1 (-4575 2675);
DOT 1 (-4000 2675);
DOT 1 (350 2750);
DOT 1 (-100 2750);
DOT 1 (350 2300);
DOT 1 (350 2800);
FORCENOTE
TP FAB3 ADD R3W10 0803
(-750 5100) 0;
DISPLAY LEFT (-750 5100);
DISPLAY 0.808511 (-750 5100);
PAINT RED (-750 5100);
FORCENOTE
TP FAB3 CHANGE R3P45 AND CONNECT TO P3V3 0803
(150 5050) 0;
DISPLAY LEFT (150 5050);
DISPLAY 0.808511 (150 5050);
PAINT RED (150 5050);
FORCENOTE
TARGET 0.7V
(500 5100) 0;
DISPLAY LEFT (500 5100);
DISPLAY 0.808511 (500 5100);
PAINT PURPLE (500 5100);
FORCENOTE
ROOM=PROC_SIDEBAND
(-5658 922) 0;
DISPLAY LEFT (-5658 922);
DISPLAY 1.276596 (-5658 922);
PAINT PURPLE (-5658 922);
FORCENOTE
BOM_COST=PROC_SIDEBAND
(-5683 822) 0;
DISPLAY LEFT (-5683 822);
DISPLAY 1.276596 (-5683 822);
PAINT PURPLE (-5683 822);
FORCENOTE
TARGET 0.7V
(700 2850) 0;
DISPLAY LEFT (700 2850);
DISPLAY 0.808511 (700 2850);
PAINT PURPLE (700 2850);
FORCENOTE
TP FAB3 CHANGE R7D33 AND CONNECT TO P3V3 0803
(400 2800) 0;
DISPLAY LEFT (400 2800);
DISPLAY 0.808511 (400 2800);
PAINT RED (400 2800);
FORCENOTE
TP FAB3 ADD R7W4 0803
(-500 2800) 0;
DISPLAY LEFT (-500 2800);
DISPLAY 0.808511 (-500 2800);
PAINT RED (-500 2800);
QUIT
